FILE_TYPE = MACRO_DRAWING;
SET COLOR_WIRE YELLOW;
SET COLOR_PROP ORANGE;
SET COLOR_DOT WHITE;
SET COLOR_ARC YELLOW;
SET COLOR_BODY GREEN;
SET COLOR_NOTE PURPLE;
SET PROP_DISPLAY VALUE;
SET PAGE_NUMBER P195;
FORCEADD Q_INDUCTOR4P_14..1
(6850 1800);
FORCEPROP 1 LAST LOCATION PL69
J 0
(6625 2055);
DISPLAY 0.489362 (6625 2055);
PAINT SKYBLUE (6625 2055);
FORCEPROP 0 LAST $SEC 1
J 0
(6625 2100);
DISPLAY 0.680851 (6625 2100);
PAINT MONO (6625 2100);
DISPLAY INVISIBLE (6625 2100);
FORCEPROP 0 LAST CDS_SEC 1
J 0
(6625 2100);
DISPLAY 1.021277 (6625 2100);
DISPLAY INVISIBLE (6625 2100);
FORCEPROP 0 LASTPIN (6450 1925) $PN 1
J 2
(6440 1935);
DISPLAY 0.489362 (6440 1935);
PAINT MONO (6440 1935);
FORCEPROP 0 LASTPIN (6450 1675) $PN 2
J 2
(6440 1685);
DISPLAY 0.489362 (6440 1685);
PAINT MONO (6440 1685);
FORCEPROP 0 LASTPIN (7250 1675) $PN 3
J 0
(7260 1685);
DISPLAY 0.489362 (7260 1685);
PAINT MONO (7260 1685);
FORCEPROP 0 LASTPIN (7250 1925) $PN 4
J 0
(7260 1935);
DISPLAY 0.489362 (7260 1935);
PAINT MONO (7260 1935);
FORCEPROP 1 LAST MATERIAL IND
J 0
(6650 1975);
DISPLAY 0.489362 (6650 1975);
PAINT SKYBLUE (6650 1975);
FORCEPROP 2 LAST PART_TYPE SMLF
J 0
(6775 1550);
DISPLAY 1.021277 (6775 1550);
FORCEPROP 2 LAST VALUE 150NH
J 0
(6750 1975);
DISPLAY 0.489362 (6750 1975);
PAINT SKYBLUE (6750 1975);
FORCEPROP 1 LAST PART_NUMBER CV+15^0TZ04
J 0
(6900 1975);
DISPLAY 0.489362 (6900 1975);
PAINT SKYBLUE (6900 1975);
FORCEPROP 2 LAST CDS_LIB pure_quanta
J 0
(6850 1800);
DISPLAY INVISIBLE (6850 1800);
FORCEPROP 1 LAST NEEDS_NO_SIZE TRUE
J 0
(6850 1800);
DISPLAY 0.468085 (6850 1800);
PAINT GREEN (6850 1800);
DISPLAY INVISIBLE (6850 1800);
FORCEPROP 1 LAST PATH I100
J 0
(7050 1955);
DISPLAY 0.723404 (7050 1955);
PAINT GREEN (7050 1955);
DISPLAY INVISIBLE (7050 1955);
FORCEADD VCC_CORE..1
(5850 3175);
FORCEPROP 3 LASTPIN (5850 3125) SIG_NAME SW_P12V_STBY_PVDDCR_CPU1_P1_FLT\g
J 0
(5860 3135);
DISPLAY 0.659574 (5860 3135);
PAINT MONO (5860 3135);
DISPLAY INVISIBLE (5860 3135);
FORCEPROP 1 LAST HDL_POWER SW_P12V_STBY_PVDDCR_CPU1_P1_FLT
J 1
(5850 3225);
DISPLAY 0.489362 (5850 3225);
PAINT GREEN (5850 3225);
FORCEPROP 2 LAST CDS_LIB pure_quanta_power
J 0
(5850 3175);
DISPLAY INVISIBLE (5850 3175);
FORCEPROP 1 LAST PATH I101
J 0
(5900 3200);
DISPLAY 0.872340 (5900 3200);
PAINT AQUA (5900 3200);
DISPLAY INVISIBLE (5900 3200);
FORCEADD Q_CAP..1
(5850 2825);
FORCEPROP 1 LAST LOCATION PC147_6
J 0
(5900 2975);
DISPLAY 0.489362 (5900 2975);
PAINT SKYBLUE (5900 2975);
FORCEPROP 0 LAST $SEC 1
J 0
(5900 3025);
DISPLAY 0.680851 (5900 3025);
PAINT MONO (5900 3025);
DISPLAY INVISIBLE (5900 3025);
FORCEPROP 0 LAST CDS_SEC 1
J 0
(5900 3025);
DISPLAY 1.021277 (5900 3025);
DISPLAY INVISIBLE (5900 3025);
FORCEPROP 1 LASTPIN (5850 2925) $PN 1
J 0
(5860 2905);
DISPLAY 0.489362 (5860 2905);
PAINT MONO (5860 2905);
FORCEPROP 1 LASTPIN (5850 2725) $PN 2
J 0
(5860 2705);
DISPLAY 0.489362 (5860 2705);
PAINT MONO (5860 2705);
FORCEPROP 1 LAST MATERIAL X6S
J 0
(5900 2775);
DISPLAY 0.489362 (5900 2775);
PAINT SKYBLUE (5900 2775);
FORCEPROP 1 LAST TOLERANCE 10%
J 0
(5900 2825);
DISPLAY 0.489362 (5900 2825);
PAINT SKYBLUE (5900 2825);
FORCEPROP 1 LAST VALUE 10UF
J 0
(5900 2925);
DISPLAY 0.489362 (5900 2925);
PAINT SKYBLUE (5900 2925);
FORCEPROP 1 LAST PART_NUMBER CH6104KEA00
J 0
(5900 2675);
DISPLAY 0.489362 (5900 2675);
PAINT SKYBLUE (5900 2675);
FORCEPROP 1 LAST VOLTAGE 25V
J 0
(5900 2875);
DISPLAY 0.489362 (5900 2875);
PAINT SKYBLUE (5900 2875);
FORCEPROP 1 LAST PACK_TYPE C0805
J 0
(5900 2725);
DISPLAY 0.489362 (5900 2725);
PAINT SKYBLUE (5900 2725);
FORCEPROP 2 LAST CDS_LIB pure_quanta
J 0
(5850 2825);
DISPLAY INVISIBLE (5850 2825);
FORCEPROP 1 LAST PATH I102
J 0
(5900 2975);
DISPLAY 0.978723 (5900 2975);
PAINT WHITE (5900 2975);
DISPLAY INVISIBLE (5900 2975);
FORCEADD Q_CAP..1
(5475 2825);
FORCEPROP 1 LAST LOCATION PC145_6
J 0
(5525 2975);
DISPLAY 0.489362 (5525 2975);
PAINT SKYBLUE (5525 2975);
FORCEPROP 0 LAST $SEC 1
J 0
(5525 3025);
DISPLAY 0.680851 (5525 3025);
PAINT MONO (5525 3025);
DISPLAY INVISIBLE (5525 3025);
FORCEPROP 0 LAST CDS_SEC 1
J 0
(5525 3025);
DISPLAY 1.021277 (5525 3025);
DISPLAY INVISIBLE (5525 3025);
FORCEPROP 1 LASTPIN (5475 2925) $PN 1
J 0
(5485 2905);
DISPLAY 0.489362 (5485 2905);
PAINT MONO (5485 2905);
FORCEPROP 1 LASTPIN (5475 2725) $PN 2
J 0
(5485 2705);
DISPLAY 0.489362 (5485 2705);
PAINT MONO (5485 2705);
FORCEPROP 1 LAST MATERIAL X6S
J 0
(5525 2775);
DISPLAY 0.489362 (5525 2775);
PAINT SKYBLUE (5525 2775);
FORCEPROP 1 LAST TOLERANCE 10%
J 0
(5525 2825);
DISPLAY 0.489362 (5525 2825);
PAINT SKYBLUE (5525 2825);
FORCEPROP 1 LAST VALUE 10UF
J 0
(5525 2925);
DISPLAY 0.489362 (5525 2925);
PAINT SKYBLUE (5525 2925);
FORCEPROP 1 LAST VOLTAGE 25V
J 0
(5525 2875);
DISPLAY 0.489362 (5525 2875);
PAINT SKYBLUE (5525 2875);
FORCEPROP 1 LAST PACK_TYPE C0805
J 0
(5525 2725);
DISPLAY 0.489362 (5525 2725);
PAINT SKYBLUE (5525 2725);
FORCEPROP 1 LAST PART_NUMBER CH6104KEA00
J 0
(5525 2675);
DISPLAY 0.489362 (5525 2675);
PAINT SKYBLUE (5525 2675);
FORCEPROP 2 LAST CDS_LIB pure_quanta
J 0
(5475 2825);
DISPLAY INVISIBLE (5475 2825);
FORCEPROP 1 LAST PATH I103
J 0
(5525 2975);
DISPLAY 0.978723 (5525 2975);
PAINT WHITE (5525 2975);
DISPLAY INVISIBLE (5525 2975);
FORCEADD UNIVERSAL_GND..1
(5850 2475);
FORCEPROP 3 LASTPIN (5850 2525) SIG_NAME GND\g
J 0
(5860 2535);
DISPLAY 0.659574 (5860 2535);
PAINT MONO (5860 2535);
DISPLAY INVISIBLE (5860 2535);
FORCEPROP 2 LAST CDS_LIB pure_quanta_power
J 0
(5850 2475);
PAINT MONO (5850 2475);
DISPLAY INVISIBLE (5850 2475);
FORCEPROP 1 LAST PATH I104
J 0
(5925 2475);
DISPLAY 0.872340 (5925 2475);
PAINT AQUA (5925 2475);
DISPLAY INVISIBLE (5925 2475);
FORCEPROP 1 LAST HDL_POWER GND
J 1
(5875 2400);
DISPLAY 0.872340 (5875 2400);
PAINT GREEN (5875 2400);
DISPLAY INVISIBLE (5875 2400);
FORCEADD Q_CAP..1
(5650 2150);
FORCEPROP 1 LAST LOCATION PC146
J 0
(5700 2250);
DISPLAY 0.489362 (5700 2250);
PAINT SKYBLUE (5700 2250);
FORCEPROP 0 LAST $SEC 1
J 0
(5700 2300);
DISPLAY 0.680851 (5700 2300);
PAINT MONO (5700 2300);
DISPLAY INVISIBLE (5700 2300);
FORCEPROP 0 LAST CDS_SEC 1
J 2
(5700 2275);
DISPLAY 1.021277 (5700 2275);
DISPLAY INVISIBLE (5700 2275);
FORCEPROP 1 LASTPIN (5650 2250) $PN 1
J 0
(5660 2230);
DISPLAY 0.489362 (5660 2230);
PAINT MONO (5660 2230);
FORCEPROP 1 LASTPIN (5650 2050) $PN 2
J 0
(5660 2030);
DISPLAY 0.489362 (5660 2030);
PAINT MONO (5660 2030);
FORCEPROP 1 LAST MATERIAL X7R
J 0
(5700 2050);
DISPLAY 0.489362 (5700 2050);
PAINT SKYBLUE (5700 2050);
FORCEPROP 1 LAST TOLERANCE 10%
J 0
(5700 2100);
DISPLAY 0.489362 (5700 2100);
PAINT SKYBLUE (5700 2100);
FORCEPROP 1 LAST VALUE 0.22UF
J 0
(5700 2200);
DISPLAY 0.489362 (5700 2200);
PAINT SKYBLUE (5700 2200);
FORCEPROP 1 LAST PART_NUMBER CH4223K1B00
J 0
(5700 2000);
DISPLAY 0.489362 (5700 2000);
PAINT SKYBLUE (5700 2000);
FORCEPROP 1 LAST VOLTAGE 16V
J 0
(5700 2150);
DISPLAY 0.489362 (5700 2150);
PAINT SKYBLUE (5700 2150);
FORCEPROP 1 LAST PACK_TYPE 0402
J 0
(5700 1950);
DISPLAY 0.489362 (5700 1950);
PAINT SKYBLUE (5700 1950);
FORCEPROP 2 LAST CDS_LIB pure_quanta
J 2
(5650 2150);
DISPLAY INVISIBLE (5650 2150);
FORCEPROP 1 LAST PATH I106
J 0
(5700 2300);
DISPLAY 0.978723 (5700 2300);
PAINT WHITE (5700 2300);
DISPLAY INVISIBLE (5700 2300);
FORCEADD Q_CAP..1
(5075 2825);
FORCEPROP 1 LAST LOCATION PC144_6
J 0
(5125 2975);
DISPLAY 0.489362 (5125 2975);
PAINT SKYBLUE (5125 2975);
FORCEPROP 0 LAST $SEC 1
J 0
(5125 3025);
DISPLAY 0.680851 (5125 3025);
PAINT MONO (5125 3025);
DISPLAY INVISIBLE (5125 3025);
FORCEPROP 0 LAST CDS_SEC 1
J 0
(5125 3025);
DISPLAY 1.021277 (5125 3025);
DISPLAY INVISIBLE (5125 3025);
FORCEPROP 1 LASTPIN (5075 2925) $PN 1
J 0
(5085 2905);
DISPLAY 0.489362 (5085 2905);
PAINT MONO (5085 2905);
FORCEPROP 1 LASTPIN (5075 2725) $PN 2
J 0
(5085 2705);
DISPLAY 0.489362 (5085 2705);
PAINT MONO (5085 2705);
FORCEPROP 1 LAST MATERIAL X6S
J 0
(5125 2775);
DISPLAY 0.489362 (5125 2775);
PAINT SKYBLUE (5125 2775);
FORCEPROP 1 LAST TOLERANCE 10%
J 0
(5125 2825);
DISPLAY 0.489362 (5125 2825);
PAINT SKYBLUE (5125 2825);
FORCEPROP 1 LAST VALUE 10UF
J 0
(5125 2925);
DISPLAY 0.489362 (5125 2925);
PAINT SKYBLUE (5125 2925);
FORCEPROP 1 LAST PART_NUMBER CH6104KEA00
J 0
(5125 2675);
DISPLAY 0.489362 (5125 2675);
PAINT SKYBLUE (5125 2675);
FORCEPROP 1 LAST VOLTAGE 25V
J 0
(5125 2875);
DISPLAY 0.489362 (5125 2875);
PAINT SKYBLUE (5125 2875);
FORCEPROP 1 LAST PACK_TYPE C0805
J 0
(5125 2725);
DISPLAY 0.489362 (5125 2725);
PAINT SKYBLUE (5125 2725);
FORCEPROP 2 LAST CDS_LIB pure_quanta
J 0
(5075 2825);
DISPLAY INVISIBLE (5075 2825);
FORCEPROP 1 LAST PATH I107
J 0
(5125 2975);
DISPLAY 0.978723 (5125 2975);
PAINT WHITE (5125 2975);
DISPLAY INVISIBLE (5125 2975);
FORCEADD Q_CAP..1
(4675 2825);
FORCEPROP 1 LAST LOCATION PC141_6
J 0
(4725 2975);
DISPLAY 0.489362 (4725 2975);
PAINT SKYBLUE (4725 2975);
FORCEPROP 0 LAST $SEC 1
J 0
(4725 3025);
DISPLAY 0.680851 (4725 3025);
PAINT MONO (4725 3025);
DISPLAY INVISIBLE (4725 3025);
FORCEPROP 0 LAST CDS_SEC 1
J 0
(4725 3025);
DISPLAY 1.021277 (4725 3025);
DISPLAY INVISIBLE (4725 3025);
FORCEPROP 1 LASTPIN (4675 2925) $PN 1
J 0
(4685 2905);
DISPLAY 0.489362 (4685 2905);
PAINT MONO (4685 2905);
FORCEPROP 1 LASTPIN (4675 2725) $PN 2
J 0
(4685 2705);
DISPLAY 0.489362 (4685 2705);
PAINT MONO (4685 2705);
FORCEPROP 1 LAST VALUE 1UF
J 0
(4725 2925);
DISPLAY 0.489362 (4725 2925);
PAINT SKYBLUE (4725 2925);
FORCEPROP 1 LAST MATERIAL X6S
J 0
(4725 2775);
DISPLAY 0.489362 (4725 2775);
PAINT SKYBLUE (4725 2775);
FORCEPROP 1 LAST TOLERANCE 10%
J 0
(4725 2825);
DISPLAY 0.489362 (4725 2825);
PAINT SKYBLUE (4725 2825);
FORCEPROP 1 LAST PART_NUMBER CH5104KEB02
J 0
(4725 2675);
DISPLAY 0.489362 (4725 2675);
PAINT SKYBLUE (4725 2675);
FORCEPROP 1 LAST VOLTAGE 25V
J 0
(4725 2875);
DISPLAY 0.489362 (4725 2875);
PAINT SKYBLUE (4725 2875);
FORCEPROP 1 LAST PACK_TYPE C0402
J 0
(4725 2725);
DISPLAY 0.489362 (4725 2725);
PAINT SKYBLUE (4725 2725);
FORCEPROP 2 LAST CDS_LIB pure_quanta
J 0
(4675 2825);
DISPLAY INVISIBLE (4675 2825);
FORCEPROP 1 LAST PATH I108
J 0
(4725 2975);
DISPLAY 0.978723 (4725 2975);
PAINT WHITE (4725 2975);
DISPLAY INVISIBLE (4725 2975);
FORCEADD Q_CAP..1
(4250 2825);
FORCEPROP 1 LAST LOCATION PC140_6
J 0
(4300 2975);
DISPLAY 0.489362 (4300 2975);
PAINT SKYBLUE (4300 2975);
FORCEPROP 0 LAST $SEC 1
J 0
(4300 2975);
DISPLAY 0.680851 (4300 2975);
PAINT MONO (4300 2975);
DISPLAY INVISIBLE (4300 2975);
FORCEPROP 0 LAST CDS_SEC 1
J 0
(4300 2975);
DISPLAY 1.021277 (4300 2975);
DISPLAY INVISIBLE (4300 2975);
FORCEPROP 1 LASTPIN (4250 2925) $PN 1
J 0
(4260 2905);
DISPLAY 0.489362 (4260 2905);
PAINT MONO (4260 2905);
FORCEPROP 1 LASTPIN (4250 2725) $PN 2
J 0
(4260 2705);
DISPLAY 0.489362 (4260 2705);
PAINT MONO (4260 2705);
FORCEPROP 1 LAST VOLTAGE 25V
J 0
(4300 2875);
DISPLAY 0.489362 (4300 2875);
PAINT SKYBLUE (4300 2875);
FORCEPROP 1 LAST MATERIAL X7R
J 0
(4300 2775);
DISPLAY 0.489362 (4300 2775);
PAINT SKYBLUE (4300 2775);
FORCEPROP 1 LAST TOLERANCE 10%
J 0
(4300 2825);
DISPLAY 0.489362 (4300 2825);
PAINT SKYBLUE (4300 2825);
FORCEPROP 1 LAST VALUE 0.1UF
J 0
(4300 2925);
DISPLAY 0.489362 (4300 2925);
PAINT SKYBLUE (4300 2925);
FORCEPROP 1 LAST PART_NUMBER CH4104K1B00
J 0
(4300 2725);
DISPLAY 0.489362 (4300 2725);
PAINT SKYBLUE (4300 2725);
FORCEPROP 1 LAST PACK_TYPE 0402
J 0
(4300 2675);
DISPLAY 0.489362 (4300 2675);
PAINT SKYBLUE (4300 2675);
FORCEPROP 2 LAST CDS_LIB pure_quanta
J 0
(4250 2825);
DISPLAY INVISIBLE (4250 2825);
FORCEPROP 1 LAST PATH I109
J 0
(4300 2975);
DISPLAY 0.978723 (4300 2975);
PAINT WHITE (4300 2975);
DISPLAY INVISIBLE (4300 2975);
FORCEADD Q_RES..1
(4750 2275);
FORCEPROP 1 LAST LOCATION PR428
J 0
(4700 2325);
DISPLAY 0.489362 (4700 2325);
PAINT SKYBLUE (4700 2325);
FORCEPROP 0 LAST $SEC 1
J 0
(5025 2375);
DISPLAY 0.680851 (5025 2375);
PAINT MONO (5025 2375);
DISPLAY INVISIBLE (5025 2375);
FORCEPROP 0 LAST CDS_SEC 1
J 0
(5025 2375);
DISPLAY 1.021277 (5025 2375);
DISPLAY INVISIBLE (5025 2375);
FORCEPROP 1 LASTPIN (4650 2275) $PN 1
J 0
(4662 2287);
DISPLAY 0.787234 (4662 2287);
PAINT MONO (4662 2287);
DISPLAY INVISIBLE (4662 2287);
FORCEPROP 1 LASTPIN (4850 2275) $PN 2
J 0
(4812 2287);
DISPLAY 0.787234 (4812 2287);
PAINT MONO (4812 2287);
DISPLAY INVISIBLE (4812 2287);
FORCEPROP 1 LAST PACK_TYPE 0402LF
J 0
(4825 2175);
DISPLAY 0.489362 (4825 2175);
PAINT SKYBLUE (4825 2175);
FORCEPROP 1 LAST TOLERANCE 1%
J 0
(4600 2175);
DISPLAY 0.489362 (4600 2175);
PAINT SKYBLUE (4600 2175);
FORCEPROP 1 LAST MATERIAL CHIP
J 0
(4850 2225);
DISPLAY 0.489362 (4850 2225);
PAINT SKYBLUE (4850 2225);
FORCEPROP 1 LAST WATTAGE 1/16W
J 2
(4950 2300);
DISPLAY 0.489362 (4950 2300);
PAINT SKYBLUE (4950 2300);
FORCEPROP 1 LAST VALUE 4.7
J 2
(4650 2325);
DISPLAY 0.489362 (4650 2325);
PAINT SKYBLUE (4650 2325);
FORCEPROP 1 LAST PART_NUMBER CS-4702FB19
J 0
(4450 2225);
DISPLAY 0.489362 (4450 2225);
PAINT SKYBLUE (4450 2225);
FORCEPROP 1 LAST PATH I110
J 0
(4700 2425);
DISPLAY 0.978723 (4700 2425);
PAINT WHITE (4700 2425);
DISPLAY INVISIBLE (4700 2425);
FORCEPROP 2 LAST CDS_LIB pure_quanta
J 0
(4750 2275);
DISPLAY INVISIBLE (4750 2275);
FORCEADD Q_RES..1
(5950 775);
FORCEPROP 1 LAST LOCATION PR429
J 0
(5900 800);
DISPLAY 0.489362 (5900 800);
PAINT SKYBLUE (5900 800);
FORCEPROP 0 LAST $SEC 1
J 0
(6200 925);
DISPLAY 0.680851 (6200 925);
PAINT MONO (6200 925);
DISPLAY INVISIBLE (6200 925);
FORCEPROP 0 LAST CDS_SEC 1
J 0
(6200 925);
DISPLAY 1.021277 (6200 925);
DISPLAY INVISIBLE (6200 925);
FORCEPROP 1 LASTPIN (5850 775) $PN 1
J 0
(5862 787);
DISPLAY 0.489362 (5862 787);
PAINT MONO (5862 787);
FORCEPROP 1 LASTPIN (6050 775) $PN 2
J 0
(6012 787);
DISPLAY 0.489362 (6012 787);
PAINT MONO (6012 787);
FORCEPROP 1 LAST WATTAGE 1/16W
J 2
(6200 800);
DISPLAY 0.489362 (6200 800);
PAINT SKYBLUE (6200 800);
FORCEPROP 1 LAST MATERIAL CHIP
J 0
(6100 675);
DISPLAY 0.489362 (6100 675);
PAINT SKYBLUE (6100 675);
FORCEPROP 1 LAST TOLERANCE 5%
J 0
(5750 675);
DISPLAY 0.489362 (5750 675);
PAINT SKYBLUE (5750 675);
FORCEPROP 1 LAST VALUE 0
J 2
(5750 800);
DISPLAY 0.489362 (5750 800);
PAINT SKYBLUE (5750 800);
FORCEPROP 1 LAST PART_NUMBER CS00002JB38
J 0
(5650 725);
DISPLAY 0.489362 (5650 725);
PAINT SKYBLUE (5650 725);
FORCEPROP 1 LAST PACK_TYPE 0402LF
J 0
(6075 725);
DISPLAY 0.489362 (6075 725);
PAINT SKYBLUE (6075 725);
FORCEPROP 2 LAST CDS_LIB pure_quanta
J 0
(5950 775);
DISPLAY INVISIBLE (5950 775);
FORCEPROP 1 LAST PATH I111
J 0
(5900 925);
DISPLAY 0.978723 (5900 925);
PAINT WHITE (5900 925);
DISPLAY INVISIBLE (5900 925);
FORCEADD Q_CAP..1
(2275 2925);
FORCEPROP 1 LAST LOCATION PC139_C1P1_6
J 0
(2325 3025);
DISPLAY 0.489362 (2325 3025);
PAINT SKYBLUE (2325 3025);
FORCEPROP 0 LAST $SEC 1
J 0
(2325 3075);
DISPLAY 0.680851 (2325 3075);
PAINT MONO (2325 3075);
DISPLAY INVISIBLE (2325 3075);
FORCEPROP 0 LAST CDS_SEC 1
J 0
(2325 3075);
DISPLAY 1.021277 (2325 3075);
DISPLAY INVISIBLE (2325 3075);
FORCEPROP 1 LASTPIN (2275 3025) $PN 1
J 0
(2285 3005);
DISPLAY 0.489362 (2285 3005);
PAINT MONO (2285 3005);
FORCEPROP 1 LASTPIN (2275 2825) $PN 2
J 0
(2285 2805);
DISPLAY 0.489362 (2285 2805);
PAINT MONO (2285 2805);
FORCEPROP 1 LAST MATERIAL X6S
J 0
(2325 2825);
DISPLAY 0.489362 (2325 2825);
PAINT SKYBLUE (2325 2825);
FORCEPROP 1 LAST TOLERANCE 10%
J 0
(2325 2875);
DISPLAY 0.489362 (2325 2875);
PAINT SKYBLUE (2325 2875);
FORCEPROP 1 LAST VALUE 2.2UF
J 0
(2325 2975);
DISPLAY 0.489362 (2325 2975);
PAINT SKYBLUE (2325 2975);
FORCEPROP 1 LAST PART_NUMBER CH5222KEB01
J 0
(2325 2775);
DISPLAY 0.489362 (2325 2775);
PAINT SKYBLUE (2325 2775);
FORCEPROP 1 LAST VOLTAGE 10V
J 0
(2325 2925);
DISPLAY 0.489362 (2325 2925);
PAINT SKYBLUE (2325 2925);
FORCEPROP 1 LAST PACK_TYPE C0402
J 0
(2325 2725);
DISPLAY 0.489362 (2325 2725);
PAINT SKYBLUE (2325 2725);
FORCEPROP 2 LAST CDS_LIB pure_quanta
J 0
(2275 2925);
DISPLAY INVISIBLE (2275 2925);
FORCEPROP 1 LAST PATH I112
J 0
(2325 3075);
DISPLAY 0.978723 (2325 3075);
PAINT WHITE (2325 3075);
DISPLAY INVISIBLE (2325 3075);
FORCEADD UNIVERSAL_GND..1
(2275 2650);
FORCEPROP 3 LASTPIN (2275 2700) SIG_NAME GND\g
J 0
(2285 2710);
DISPLAY 0.659574 (2285 2710);
PAINT MONO (2285 2710);
DISPLAY INVISIBLE (2285 2710);
FORCEPROP 2 LAST CDS_LIB pure_quanta_power
J 0
(2275 2650);
DISPLAY INVISIBLE (2275 2650);
FORCEPROP 1 LAST PATH I113
J 0
(2350 2650);
DISPLAY 0.872340 (2350 2650);
PAINT AQUA (2350 2650);
DISPLAY INVISIBLE (2350 2650);
FORCEPROP 1 LAST HDL_POWER GND
J 1
(2300 2575);
DISPLAY 0.872340 (2300 2575);
PAINT GREEN (2300 2575);
DISPLAY INVISIBLE (2300 2575);
FORCEADD Q_RES..2
(1925 2900);
FORCEPROP 1 LAST LOCATION PR427
J 0
(1970 3025);
DISPLAY 0.489362 (1970 3025);
PAINT SKYBLUE (1970 3025);
FORCEPROP 0 LAST $SEC 1
J 0
(1975 3075);
DISPLAY 0.680851 (1975 3075);
PAINT MONO (1975 3075);
DISPLAY INVISIBLE (1975 3075);
FORCEPROP 0 LAST CDS_SEC 1
J 0
(1975 3075);
DISPLAY 1.021277 (1975 3075);
DISPLAY INVISIBLE (1975 3075);
FORCEPROP 1 LASTPIN (1925 3000) $PN 1
J 0
(1930 2962);
DISPLAY 0.489362 (1930 2962);
PAINT MONO (1930 2962);
FORCEPROP 1 LASTPIN (1925 2800) $PN 2
J 0
(1930 2810);
DISPLAY 0.489362 (1930 2810);
PAINT MONO (1930 2810);
FORCEPROP 1 LAST WATTAGE 1/16W
J 0
(1975 2875);
DISPLAY 0.489362 (1975 2875);
PAINT SKYBLUE (1975 2875);
FORCEPROP 1 LAST MATERIAL CHIP
J 0
(1975 2825);
DISPLAY 0.489362 (1975 2825);
PAINT SKYBLUE (1975 2825);
FORCEPROP 1 LAST TOLERANCE 1%
J 0
(1975 2925);
DISPLAY 0.489362 (1975 2925);
PAINT SKYBLUE (1975 2925);
FORCEPROP 1 LAST VALUE 2.2
J 0
(1975 2975);
DISPLAY 0.489362 (1975 2975);
PAINT SKYBLUE (1975 2975);
FORCEPROP 1 LAST PART_NUMBER CS-2202FB00
J 0
(1975 2775);
DISPLAY 0.489362 (1975 2775);
PAINT SKYBLUE (1975 2775);
FORCEPROP 1 LAST PACK_TYPE 0402LF
J 0
(1975 2725);
DISPLAY 0.489362 (1975 2725);
PAINT SKYBLUE (1975 2725);
FORCEPROP 2 LAST CDS_LIB pure_quanta
J 0
(1925 2900);
DISPLAY INVISIBLE (1925 2900);
FORCEPROP 1 LAST PATH I115
J 0
(1975 3075);
DISPLAY 0.978723 (1975 3075);
PAINT WHITE (1975 3075);
DISPLAY INVISIBLE (1975 3075);
FORCEADD Q_CAP..1
(1925 2350);
FORCEPROP 1 LAST LOCATION PC138
J 0
(1975 2450);
DISPLAY 0.489362 (1975 2450);
PAINT SKYBLUE (1975 2450);
FORCEPROP 0 LAST $SEC 1
J 0
(1975 2500);
DISPLAY 0.680851 (1975 2500);
PAINT MONO (1975 2500);
DISPLAY INVISIBLE (1975 2500);
FORCEPROP 0 LAST CDS_SEC 1
J 0
(1975 2500);
DISPLAY 1.021277 (1975 2500);
DISPLAY INVISIBLE (1975 2500);
FORCEPROP 1 LASTPIN (1925 2450) $PN 1
J 0
(1935 2430);
DISPLAY 0.489362 (1935 2430);
PAINT MONO (1935 2430);
FORCEPROP 1 LASTPIN (1925 2250) $PN 2
J 0
(1935 2230);
DISPLAY 0.489362 (1935 2230);
PAINT MONO (1935 2230);
FORCEPROP 1 LAST MATERIAL X6S
J 0
(1975 2250);
DISPLAY 0.489362 (1975 2250);
PAINT SKYBLUE (1975 2250);
FORCEPROP 1 LAST TOLERANCE 10%
J 0
(1975 2300);
DISPLAY 0.489362 (1975 2300);
PAINT SKYBLUE (1975 2300);
FORCEPROP 1 LAST VALUE 2.2UF
J 0
(1975 2400);
DISPLAY 0.489362 (1975 2400);
PAINT SKYBLUE (1975 2400);
FORCEPROP 1 LAST PART_NUMBER CH5222KEB01
J 0
(1975 2200);
DISPLAY 0.489362 (1975 2200);
PAINT SKYBLUE (1975 2200);
FORCEPROP 1 LAST VOLTAGE 10V
J 0
(1975 2350);
DISPLAY 0.489362 (1975 2350);
PAINT SKYBLUE (1975 2350);
FORCEPROP 1 LAST PACK_TYPE C0402
J 0
(1975 2150);
DISPLAY 0.489362 (1975 2150);
PAINT SKYBLUE (1975 2150);
FORCEPROP 2 LAST CDS_LIB pure_quanta
J 0
(1925 2350);
DISPLAY INVISIBLE (1925 2350);
FORCEPROP 1 LAST PATH I116
J 0
(1975 2500);
DISPLAY 0.978723 (1975 2500);
PAINT WHITE (1975 2500);
DISPLAY INVISIBLE (1975 2500);
FORCEADD UNIVERSAL_GND..1
(1925 2150);
FORCEPROP 3 LASTPIN (1925 2200) SIG_NAME GND\g
J 0
(1935 2210);
DISPLAY 0.659574 (1935 2210);
PAINT MONO (1935 2210);
DISPLAY INVISIBLE (1935 2210);
FORCEPROP 2 LAST CDS_LIB pure_quanta_power
J 0
(1925 2150);
DISPLAY INVISIBLE (1925 2150);
FORCEPROP 1 LAST PATH I117
J 0
(2000 2150);
DISPLAY 0.872340 (2000 2150);
PAINT AQUA (2000 2150);
DISPLAY INVISIBLE (2000 2150);
FORCEPROP 1 LAST HDL_POWER GND
J 1
(1950 2075);
DISPLAY 0.872340 (1950 2075);
PAINT GREEN (1950 2075);
DISPLAY INVISIBLE (1950 2075);
FORCEADD OFFPAGE..5
(1950 1925);
FORCEPROP 2 LAST $XR0 193 
J 0
(1695 1925);
DISPLAY 0.638298 (1695 1925);
PAINT MONO (1695 1925);
FORCEPROP 2 LAST PATH I118
J 0
(1675 1975);
DISPLAY 1.021277 (1675 1975);
DISPLAY INVISIBLE (1675 1975);
FORCEPROP 1 LAST COMMENT_BODY TRUE
J 0
(2050 1850);
DISPLAY 0.872340 (2050 1850);
PAINT GREEN (2050 1850);
DISPLAY INVISIBLE (2050 1850);
FORCEPROP 1 LAST OFFPAGE TRUE
J 0
(2275 1800);
DISPLAY 0.872340 (2275 1800);
PAINT GREEN (2275 1800);
DISPLAY INVISIBLE (2275 1800);
FORCEPROP 2 LAST CDS_LIB standard
J 0
(1950 1925);
DISPLAY INVISIBLE (1950 1925);
FORCEADD OFFPAGE..1
(1950 1825);
FORCEPROP 2 LAST $XR5 199 
J 0
(1098 1825);
DISPLAY 0.638298 (1098 1825);
PAINT MONO (1098 1825);
FORCEPROP 2 LAST $XR4 198 
J 0
(1218 1825);
DISPLAY 0.638298 (1218 1825);
PAINT MONO (1218 1825);
FORCEPROP 2 LAST $XR3 196 
J 0
(1338 1825);
DISPLAY 0.638298 (1338 1825);
PAINT MONO (1338 1825);
FORCEPROP 2 LAST $XR2 195 
J 0
(1458 1825);
DISPLAY 0.638298 (1458 1825);
PAINT MONO (1458 1825);
FORCEPROP 2 LAST $XR1 194 
J 0
(1578 1825);
DISPLAY 0.638298 (1578 1825);
PAINT MONO (1578 1825);
FORCEPROP 2 LAST $XR0 193 
J 0
(1698 1825);
DISPLAY 0.638298 (1698 1825);
PAINT MONO (1698 1825);
FORCEPROP 2 LAST PATH I119
J 0
(1700 1875);
DISPLAY 1.021277 (1700 1875);
DISPLAY INVISIBLE (1700 1875);
FORCEPROP 1 LAST COMMENT_BODY TRUE
J 0
(2075 1725);
DISPLAY 0.872340 (2075 1725);
PAINT GREEN (2075 1725);
DISPLAY INVISIBLE (2075 1725);
FORCEPROP 1 LAST OFFPAGE TRUE
J 0
(2275 1700);
DISPLAY 0.872340 (2275 1700);
PAINT GREEN (2275 1700);
DISPLAY INVISIBLE (2275 1700);
FORCEPROP 2 LAST CDS_LIB standard
J 0
(1950 1825);
DISPLAY INVISIBLE (1950 1825);
FORCEADD UNIVERSAL_GND..1
(4050 1200);
FORCEPROP 3 LASTPIN (4050 1250) SIG_NAME GND\g
J 0
(4060 1260);
DISPLAY 0.659574 (4060 1260);
PAINT MONO (4060 1260);
DISPLAY INVISIBLE (4060 1260);
FORCEPROP 2 LAST CDS_LIB pure_quanta_power
J 0
(4050 1200);
PAINT MONO (4050 1200);
DISPLAY INVISIBLE (4050 1200);
FORCEPROP 1 LAST PATH I120
J 0
(4125 1200);
DISPLAY 0.872340 (4125 1200);
PAINT AQUA (4125 1200);
DISPLAY INVISIBLE (4125 1200);
FORCEPROP 1 LAST HDL_POWER GND
J 1
(4075 1125);
DISPLAY 0.872340 (4075 1125);
PAINT GREEN (4075 1125);
DISPLAY INVISIBLE (4075 1125);
FORCEADD OFFPAGE..1
(1950 1325);
FORCEPROP 2 LAST $XR0 193 
J 0
(1698 1325);
DISPLAY 0.638298 (1698 1325);
PAINT MONO (1698 1325);
FORCEPROP 2 LAST PATH I121
J 0
(1700 1375);
DISPLAY 1.021277 (1700 1375);
DISPLAY INVISIBLE (1700 1375);
FORCEPROP 1 LAST COMMENT_BODY TRUE
J 0
(2075 1225);
DISPLAY 0.872340 (2075 1225);
PAINT GREEN (2075 1225);
DISPLAY INVISIBLE (2075 1225);
FORCEPROP 1 LAST OFFPAGE TRUE
J 0
(2275 1200);
DISPLAY 0.872340 (2275 1200);
PAINT GREEN (2275 1200);
DISPLAY INVISIBLE (2275 1200);
FORCEPROP 2 LAST CDS_LIB standard
J 0
(1950 1325);
DISPLAY INVISIBLE (1950 1325);
FORCEADD OFFPAGE..5
(1950 1425);
FORCEPROP 2 LAST $XR3 193 
J 0
(1695 1497);
DISPLAY 0.638298 (1695 1497);
PAINT MONO (1695 1497);
FORCEPROP 2 LAST $XR2 196 
J 0
(1695 1461);
DISPLAY 0.638298 (1695 1461);
PAINT MONO (1695 1461);
FORCEPROP 2 LAST $XR1 195 
J 0
(1695 1389);
DISPLAY 0.638298 (1695 1389);
PAINT MONO (1695 1389);
FORCEPROP 2 LAST $XR0 194 
J 0
(1695 1425);
DISPLAY 0.638298 (1695 1425);
PAINT MONO (1695 1425);
FORCEPROP 2 LAST PATH I122
J 0
(1675 1500);
DISPLAY 1.021277 (1675 1500);
DISPLAY INVISIBLE (1675 1500);
FORCEPROP 1 LAST COMMENT_BODY TRUE
J 0
(2050 1350);
DISPLAY 0.872340 (2050 1350);
PAINT GREEN (2050 1350);
DISPLAY INVISIBLE (2050 1350);
FORCEPROP 1 LAST OFFPAGE TRUE
J 0
(2275 1300);
DISPLAY 0.872340 (2275 1300);
PAINT GREEN (2275 1300);
DISPLAY INVISIBLE (2275 1300);
FORCEPROP 2 LAST CDS_LIB standard
J 0
(1950 1425);
DISPLAY INVISIBLE (1950 1425);
FORCEADD Q_RES..2
R 2
(1475 1425);
FORCEPROP 1 LAST LOCATION PR426
J 2
(1430 1550);
DISPLAY 0.489362 (1430 1550);
PAINT SKYBLUE (1430 1550);
FORCEPROP 0 LAST $SEC 1
J 0
(1450 1600);
DISPLAY 0.680851 (1450 1600);
PAINT MONO (1450 1600);
DISPLAY INVISIBLE (1450 1600);
FORCEPROP 0 LAST CDS_SEC 1
J 0
(1450 1600);
DISPLAY 1.021277 (1450 1600);
DISPLAY INVISIBLE (1450 1600);
FORCEPROP 1 LASTPIN (1475 1525) $PN 1
J 2
(1470 1487);
DISPLAY 0.489362 (1470 1487);
PAINT MONO (1470 1487);
FORCEPROP 1 LASTPIN (1475 1325) $PN 2
J 2
(1470 1335);
DISPLAY 0.489362 (1470 1335);
PAINT MONO (1470 1335);
FORCEPROP 1 LAST WATTAGE 1/16W
J 2
(1435 1400);
DISPLAY 0.489362 (1435 1400);
PAINT SKYBLUE (1435 1400);
FORCEPROP 1 LAST MATERIAL EMPTY
J 2
(1435 1350);
DISPLAY 0.489362 (1435 1350);
PAINT RED (1435 1350);
FORCEPROP 1 LAST TOLERANCE 1%
J 2
(1430 1450);
DISPLAY 0.489362 (1430 1450);
PAINT SKYBLUE (1430 1450);
FORCEPROP 1 LAST VALUE 8.87K
J 2
(1430 1500);
DISPLAY 0.489362 (1430 1500);
PAINT SKYBLUE (1430 1500);
FORCEPROP 1 LAST PART_NUMBER CS28872FB01
J 2
(1435 1300);
DISPLAY 0.489362 (1435 1300);
PAINT SKYBLUE (1435 1300);
FORCEPROP 1 LAST PACK_TYPE 0402LF
J 2
(1435 1250);
DISPLAY 0.489362 (1435 1250);
PAINT SKYBLUE (1435 1250);
FORCEPROP 2 LAST CDS_LIB pure_quanta
J 2
(1475 1425);
DISPLAY INVISIBLE (1475 1425);
FORCEPROP 1 LAST PATH I123
J 2
(1425 1600);
DISPLAY 0.978723 (1425 1600);
PAINT WHITE (1425 1600);
DISPLAY INVISIBLE (1425 1600);
FORCEADD UNIVERSAL_GND..1
(1475 1200);
FORCEPROP 3 LASTPIN (1475 1250) SIG_NAME GND\g
J 0
(1485 1260);
DISPLAY 0.659574 (1485 1260);
PAINT MONO (1485 1260);
DISPLAY INVISIBLE (1485 1260);
FORCEPROP 2 LAST CDS_LIB pure_quanta_power
J 0
(1475 1200);
PAINT MONO (1475 1200);
DISPLAY INVISIBLE (1475 1200);
FORCEPROP 1 LAST PATH I124
J 0
(1550 1200);
DISPLAY 0.872340 (1550 1200);
PAINT AQUA (1550 1200);
DISPLAY INVISIBLE (1550 1200);
FORCEPROP 1 LAST HDL_POWER GND
J 1
(1500 1125);
DISPLAY 0.872340 (1500 1125);
PAINT GREEN (1500 1125);
DISPLAY INVISIBLE (1500 1125);
FORCEADD Q_CAP..1
(975 1550);
FORCEPROP 1 LAST LOCATION PC136_6
J 0
(1025 1650);
DISPLAY 0.489362 (1025 1650);
PAINT SKYBLUE (1025 1650);
FORCEPROP 0 LAST $SEC 1
J 0
(1025 1675);
DISPLAY 0.680851 (1025 1675);
PAINT MONO (1025 1675);
DISPLAY INVISIBLE (1025 1675);
FORCEPROP 0 LAST CDS_SEC 1
J 0
(1225 1600);
DISPLAY 1.021277 (1225 1600);
DISPLAY INVISIBLE (1225 1600);
FORCEPROP 1 LASTPIN (975 1650) $PN 1
J 0
(985 1630);
DISPLAY 0.489362 (985 1630);
PAINT MONO (985 1630);
FORCEPROP 1 LASTPIN (975 1450) $PN 2
J 0
(985 1430);
DISPLAY 0.489362 (985 1430);
PAINT MONO (985 1430);
FORCEPROP 1 LAST MATERIAL X7R
J 0
(1025 1450);
DISPLAY 0.489362 (1025 1450);
PAINT SKYBLUE (1025 1450);
FORCEPROP 1 LAST TOLERANCE 10%
J 0
(1025 1500);
DISPLAY 0.489362 (1025 1500);
PAINT SKYBLUE (1025 1500);
FORCEPROP 1 LAST VALUE 0.1UF
J 0
(1025 1600);
DISPLAY 0.489362 (1025 1600);
PAINT SKYBLUE (1025 1600);
FORCEPROP 1 LAST PART_NUMBER CH4104K1B00
J 0
(1025 1400);
DISPLAY 0.489362 (1025 1400);
PAINT SKYBLUE (1025 1400);
FORCEPROP 1 LAST VOLTAGE 25V
J 0
(1025 1550);
DISPLAY 0.489362 (1025 1550);
PAINT SKYBLUE (1025 1550);
FORCEPROP 1 LAST PACK_TYPE 0402
J 0
(1025 1350);
DISPLAY 0.489362 (1025 1350);
PAINT SKYBLUE (1025 1350);
FORCEPROP 2 LAST CDS_LIB pure_quanta
J 0
(975 1550);
DISPLAY INVISIBLE (975 1550);
FORCEPROP 1 LAST PATH I125
J 0
(1025 1700);
DISPLAY 0.978723 (1025 1700);
PAINT WHITE (1025 1700);
DISPLAY INVISIBLE (1025 1700);
FORCEADD UNIVERSAL_GND..1
(975 1350);
FORCEPROP 3 LASTPIN (975 1400) SIG_NAME GND\g
J 0
(985 1410);
DISPLAY 0.659574 (985 1410);
PAINT MONO (985 1410);
DISPLAY INVISIBLE (985 1410);
FORCEPROP 2 LAST CDS_LIB pure_quanta_power
J 0
(975 1350);
DISPLAY INVISIBLE (975 1350);
FORCEPROP 1 LAST PATH I126
J 0
(1050 1350);
DISPLAY 0.872340 (1050 1350);
PAINT AQUA (1050 1350);
DISPLAY INVISIBLE (1050 1350);
FORCEPROP 1 LAST HDL_POWER GND
J 1
(1000 1275);
DISPLAY 0.872340 (1000 1275);
PAINT GREEN (1000 1275);
DISPLAY INVISIBLE (1000 1275);
FORCEADD UNIVERSAL_GND..1
(4925 975);
FORCEPROP 3 LASTPIN (4925 1025) SIG_NAME GND\g
J 0
(4935 1035);
DISPLAY 0.659574 (4935 1035);
PAINT MONO (4935 1035);
DISPLAY INVISIBLE (4935 1035);
FORCEPROP 2 LAST CDS_LIB pure_quanta_power
J 0
(4925 975);
DISPLAY INVISIBLE (4925 975);
FORCEPROP 1 LAST PATH I127
J 0
(5000 975);
DISPLAY 0.872340 (5000 975);
PAINT AQUA (5000 975);
DISPLAY INVISIBLE (5000 975);
FORCEPROP 1 LAST HDL_POWER GND
J 1
(4950 900);
DISPLAY 0.872340 (4950 900);
PAINT GREEN (4950 900);
DISPLAY INVISIBLE (4950 900);
FORCEADD Q_RES..2
(4925 1200);
FORCEPROP 1 LAST LOCATION PR518
J 0
(4970 1325);
DISPLAY 0.489362 (4970 1325);
PAINT SKYBLUE (4970 1325);
FORCEPROP 0 LAST $SEC 1
J 0
(4975 1375);
DISPLAY 0.680851 (4975 1375);
PAINT MONO (4975 1375);
DISPLAY INVISIBLE (4975 1375);
FORCEPROP 0 LAST CDS_SEC 1
J 0
(4975 1375);
DISPLAY 1.021277 (4975 1375);
DISPLAY INVISIBLE (4975 1375);
FORCEPROP 1 LASTPIN (4925 1300) $PN 1
J 0
(4930 1262);
DISPLAY 0.489362 (4930 1262);
PAINT MONO (4930 1262);
FORCEPROP 1 LASTPIN (4925 1100) $PN 2
J 0
(4930 1110);
DISPLAY 0.489362 (4930 1110);
PAINT MONO (4930 1110);
FORCEPROP 1 LAST PACK_TYPE 0402LF
J 0
(4965 1025);
DISPLAY 0.489362 (4965 1025);
PAINT SKYBLUE (4965 1025);
FORCEPROP 1 LAST PART_NUMBER CS-1504FB00
J 0
(4965 1075);
DISPLAY 0.489362 (4965 1075);
PAINT SKYBLUE (4965 1075);
FORCEPROP 1 LAST MATERIAL EMPTY
J 0
(4965 1125);
DISPLAY 0.489362 (4965 1125);
PAINT RED (4965 1125);
FORCEPROP 1 LAST WATTAGE 1/8W
J 0
(4965 1175);
DISPLAY 0.489362 (4965 1175);
PAINT SKYBLUE (4965 1175);
FORCEPROP 1 LAST TOLERANCE 1%
J 0
(4970 1225);
DISPLAY 0.489362 (4970 1225);
PAINT SKYBLUE (4970 1225);
FORCEPROP 1 LAST VALUE 1.5
J 0
(4970 1275);
DISPLAY 0.489362 (4970 1275);
PAINT SKYBLUE (4970 1275);
FORCEPROP 2 LAST CDS_LIB pure_quanta
J 0
(4925 1200);
DISPLAY INVISIBLE (4925 1200);
FORCEPROP 1 LAST PATH I128
J 0
(4975 1375);
DISPLAY 0.978723 (4975 1375);
PAINT WHITE (4975 1375);
DISPLAY INVISIBLE (4975 1375);
FORCEADD Q_CAP..1
(4925 1725);
FORCEPROP 1 LAST LOCATION PC208
J 0
(4975 1825);
DISPLAY 0.489362 (4975 1825);
PAINT SKYBLUE (4975 1825);
FORCEPROP 0 LAST $SEC 1
J 0
(4975 1875);
DISPLAY 0.680851 (4975 1875);
PAINT MONO (4975 1875);
DISPLAY INVISIBLE (4975 1875);
FORCEPROP 0 LAST CDS_SEC 1
J 0
(4975 1875);
DISPLAY 1.021277 (4975 1875);
DISPLAY INVISIBLE (4975 1875);
FORCEPROP 1 LASTPIN (4925 1825) $PN 1
J 0
(4935 1805);
DISPLAY 0.489362 (4935 1805);
PAINT MONO (4935 1805);
FORCEPROP 1 LASTPIN (4925 1625) $PN 2
J 0
(4935 1605);
DISPLAY 0.489362 (4935 1605);
PAINT MONO (4935 1605);
FORCEPROP 1 LAST PART_NUMBER CH1566K1B09
J 0
(4975 1575);
DISPLAY 0.489362 (4975 1575);
PAINT SKYBLUE (4975 1575);
FORCEPROP 1 LAST PACK_TYPE C0402
J 0
(4975 1525);
DISPLAY 0.489362 (4975 1525);
PAINT SKYBLUE (4975 1525);
FORCEPROP 1 LAST VALUE 560PF
J 0
(4975 1775);
DISPLAY 0.489362 (4975 1775);
PAINT SKYBLUE (4975 1775);
FORCEPROP 1 LAST VOLTAGE 50V
J 0
(4975 1725);
DISPLAY 0.489362 (4975 1725);
PAINT SKYBLUE (4975 1725);
FORCEPROP 1 LAST TOLERANCE 10%
J 0
(4975 1675);
DISPLAY 0.489362 (4975 1675);
PAINT SKYBLUE (4975 1675);
FORCEPROP 1 LAST MATERIAL EMPTY
J 0
(4975 1625);
DISPLAY 0.489362 (4975 1625);
PAINT RED (4975 1625);
FORCEPROP 2 LAST CDS_LIB pure_quanta
J 0
(4925 1725);
DISPLAY INVISIBLE (4925 1725);
FORCEPROP 1 LAST PATH I129
J 0
(4975 1875);
DISPLAY 0.978723 (4975 1875);
PAINT WHITE (4975 1875);
DISPLAY INVISIBLE (4975 1875);
FORCEADD UNIVERSAL_GND..1
(4850 3650);
FORCEPROP 3 LASTPIN (4850 3700) SIG_NAME GND\g
J 0
(4860 3710);
DISPLAY 0.659574 (4860 3710);
PAINT MONO (4860 3710);
DISPLAY INVISIBLE (4860 3710);
FORCEPROP 2 LAST CDS_LIB pure_quanta_power
J 0
(4850 3650);
DISPLAY INVISIBLE (4850 3650);
FORCEPROP 1 LAST PATH I130
J 0
(4925 3650);
DISPLAY 0.872340 (4925 3650);
PAINT AQUA (4925 3650);
DISPLAY INVISIBLE (4925 3650);
FORCEPROP 1 LAST HDL_POWER GND
J 1
(4875 3575);
DISPLAY 0.872340 (4875 3575);
PAINT GREEN (4875 3575);
DISPLAY INVISIBLE (4875 3575);
FORCEADD Q_RES..2
(4850 3875);
FORCEPROP 1 LAST LOCATION PR517
J 0
(4895 4000);
DISPLAY 0.489362 (4895 4000);
PAINT SKYBLUE (4895 4000);
FORCEPROP 0 LAST $SEC 1
J 0
(4900 4050);
DISPLAY 0.680851 (4900 4050);
PAINT MONO (4900 4050);
DISPLAY INVISIBLE (4900 4050);
FORCEPROP 0 LAST CDS_SEC 1
J 0
(4900 4050);
DISPLAY 1.021277 (4900 4050);
DISPLAY INVISIBLE (4900 4050);
FORCEPROP 1 LASTPIN (4850 3975) $PN 1
J 0
(4855 3937);
DISPLAY 0.489362 (4855 3937);
PAINT MONO (4855 3937);
FORCEPROP 1 LASTPIN (4850 3775) $PN 2
J 0
(4855 3785);
DISPLAY 0.489362 (4855 3785);
PAINT MONO (4855 3785);
FORCEPROP 1 LAST WATTAGE 1/8W
J 0
(4890 3850);
DISPLAY 0.489362 (4890 3850);
PAINT SKYBLUE (4890 3850);
FORCEPROP 1 LAST MATERIAL EMPTY
J 0
(4890 3800);
DISPLAY 0.489362 (4890 3800);
PAINT RED (4890 3800);
FORCEPROP 1 LAST TOLERANCE 1%
J 0
(4895 3900);
DISPLAY 0.489362 (4895 3900);
PAINT SKYBLUE (4895 3900);
FORCEPROP 1 LAST VALUE 1.5
J 0
(4895 3950);
DISPLAY 0.489362 (4895 3950);
PAINT SKYBLUE (4895 3950);
FORCEPROP 1 LAST PART_NUMBER CS-1504FB00
J 0
(4890 3750);
DISPLAY 0.489362 (4890 3750);
PAINT SKYBLUE (4890 3750);
FORCEPROP 1 LAST PACK_TYPE 0402LF
J 0
(4890 3700);
DISPLAY 0.489362 (4890 3700);
PAINT SKYBLUE (4890 3700);
FORCEPROP 2 LAST CDS_LIB pure_quanta
J 0
(4850 3875);
DISPLAY INVISIBLE (4850 3875);
FORCEPROP 1 LAST PATH I131
J 0
(4900 4050);
DISPLAY 0.978723 (4900 4050);
PAINT WHITE (4900 4050);
DISPLAY INVISIBLE (4900 4050);
FORCEADD Q_CAP..1
(4850 4350);
FORCEPROP 1 LAST LOCATION PC207
J 0
(4900 4450);
DISPLAY 0.489362 (4900 4450);
PAINT SKYBLUE (4900 4450);
FORCEPROP 0 LAST $SEC 1
J 0
(4900 4500);
DISPLAY 0.680851 (4900 4500);
PAINT MONO (4900 4500);
DISPLAY INVISIBLE (4900 4500);
FORCEPROP 0 LAST CDS_SEC 1
J 0
(4900 4500);
DISPLAY 1.021277 (4900 4500);
DISPLAY INVISIBLE (4900 4500);
FORCEPROP 1 LASTPIN (4850 4450) $PN 1
J 0
(4860 4430);
DISPLAY 0.489362 (4860 4430);
PAINT MONO (4860 4430);
FORCEPROP 1 LASTPIN (4850 4250) $PN 2
J 0
(4860 4230);
DISPLAY 0.489362 (4860 4230);
PAINT MONO (4860 4230);
FORCEPROP 1 LAST MATERIAL EMPTY
J 0
(4900 4250);
DISPLAY 0.489362 (4900 4250);
PAINT RED (4900 4250);
FORCEPROP 1 LAST TOLERANCE 10%
J 0
(4900 4300);
DISPLAY 0.489362 (4900 4300);
PAINT SKYBLUE (4900 4300);
FORCEPROP 1 LAST VALUE 560PF
J 0
(4900 4400);
DISPLAY 0.489362 (4900 4400);
PAINT SKYBLUE (4900 4400);
FORCEPROP 1 LAST PART_NUMBER CH1566K1B09
J 0
(4900 4200);
DISPLAY 0.489362 (4900 4200);
PAINT SKYBLUE (4900 4200);
FORCEPROP 1 LAST VOLTAGE 50V
J 0
(4900 4350);
DISPLAY 0.489362 (4900 4350);
PAINT SKYBLUE (4900 4350);
FORCEPROP 1 LAST PACK_TYPE C0402
J 0
(4900 4150);
DISPLAY 0.489362 (4900 4150);
PAINT SKYBLUE (4900 4150);
FORCEPROP 2 LAST CDS_LIB pure_quanta
J 0
(4850 4350);
DISPLAY INVISIBLE (4850 4350);
FORCEPROP 1 LAST PATH I132
J 0
(4900 4500);
DISPLAY 0.978723 (4900 4500);
PAINT WHITE (4900 4500);
DISPLAY INVISIBLE (4900 4500);
FORCEADD VCC_CORE..1
(1875 5925);
FORCEPROP 3 LASTPIN (1875 5875) SIG_NAME PVDDCR_CPU1_P1_PVCC\g
J 0
(1885 5885);
DISPLAY 0.659574 (1885 5885);
PAINT MONO (1885 5885);
DISPLAY INVISIBLE (1885 5885);
FORCEPROP 1 LAST HDL_POWER PVDDCR_CPU1_P1_PVCC
J 1
(1875 5975);
DISPLAY 0.489362 (1875 5975);
PAINT GREEN (1875 5975);
FORCEPROP 2 LAST CDS_LIB pure_quanta_power
J 0
(1875 5925);
DISPLAY INVISIBLE (1875 5925);
FORCEPROP 1 LAST PATH I133
J 0
(1925 5950);
DISPLAY 0.872340 (1925 5950);
PAINT AQUA (1925 5950);
DISPLAY INVISIBLE (1925 5950);
FORCEADD VCC_CORE..1
(1925 3300);
FORCEPROP 3 LASTPIN (1925 3250) SIG_NAME PVDDCR_CPU1_P1_PVCC\g
J 0
(1935 3260);
DISPLAY 0.659574 (1935 3260);
PAINT MONO (1935 3260);
DISPLAY INVISIBLE (1935 3260);
FORCEPROP 1 LAST HDL_POWER PVDDCR_CPU1_P1_PVCC
J 1
(1925 3350);
DISPLAY 0.489362 (1925 3350);
PAINT GREEN (1925 3350);
FORCEPROP 2 LAST CDS_LIB pure_quanta_power
J 0
(1925 3300);
DISPLAY INVISIBLE (1925 3300);
FORCEPROP 1 LAST PATH I134
J 0
(1975 3325);
DISPLAY 0.872340 (1975 3325);
PAINT AQUA (1975 3325);
DISPLAY INVISIBLE (1975 3325);
FORCEADD UNIVERSAL_GND..1
(5575 1575);
FORCEPROP 3 LASTPIN (5575 1625) SIG_NAME GND\g
J 0
(5585 1635);
DISPLAY 0.659574 (5585 1635);
PAINT MONO (5585 1635);
DISPLAY INVISIBLE (5585 1635);
FORCEPROP 2 LAST CDS_LIB pure_quanta_power
J 0
(5575 1575);
DISPLAY INVISIBLE (5575 1575);
FORCEPROP 1 LAST PATH I135
J 0
(5650 1575);
DISPLAY 0.872340 (5650 1575);
PAINT AQUA (5650 1575);
DISPLAY INVISIBLE (5650 1575);
FORCEPROP 1 LAST HDL_POWER GND
J 1
(5600 1500);
DISPLAY 0.872340 (5600 1500);
PAINT GREEN (5600 1500);
DISPLAY INVISIBLE (5600 1500);
FORCEADD Q_INDUCTOR..1
R 2
(5775 1700);
FORCEPROP 1 LAST LOCATION PL39
J 0
(5625 1850);
DISPLAY 0.489362 (5625 1850);
PAINT SKYBLUE (5625 1850);
FORCEPROP 0 LAST $SEC 1
J 0
(5625 1875);
DISPLAY 0.680851 (5625 1875);
PAINT MONO (5625 1875);
DISPLAY INVISIBLE (5625 1875);
FORCEPROP 0 LAST CDS_SEC 1
J 0
(5625 1875);
DISPLAY 0.680851 (5625 1875);
DISPLAY INVISIBLE (5625 1875);
FORCEPROP 0 LASTPIN (5875 1675) $PN 1
J 0
(5885 1685);
DISPLAY 0.489362 (5885 1685);
PAINT MONO (5885 1685);
FORCEPROP 0 LASTPIN (5675 1675) $PN 2
J 2
(5665 1685);
DISPLAY 0.489362 (5665 1685);
PAINT MONO (5665 1685);
FORCEPROP 1 LAST PART_NUMBER CV+22Y0EZ00
J 0
(5625 1775);
DISPLAY 0.489362 (5625 1775);
PAINT SKYBLUE (5625 1775);
FORCEPROP 2 LAST PACK_TYPE SMLF
J 0
(5625 1800);
DISPLAY 0.489362 (5625 1800);
PAINT SKYBLUE (5625 1800);
FORCEPROP 1 LAST MATERIAL IND
J 0
(5625 1750);
DISPLAY 0.489362 (5625 1750);
PAINT SKYBLUE (5625 1750);
FORCEPROP 2 LASTPIN (5875 1675) SIG_NAME IND_CPU1_P1_CPL0
J 0
(5865 1685);
DISPLAY 0.489362 (5865 1685);
FORCEPROP 2 LASTPROP $XRERR UNIQUE?
J 0
(5625 1685);
DISPLAY 0.638298 (5625 1685);
PAINT MONO (5625 1685);
DISPLAY INVISIBLE (5625 1685);
FORCEPROP 2 LAST VALUE 0.22UH/33A
J 0
(5625 1825);
DISPLAY 0.489362 (5625 1825);
PAINT SKYBLUE (5625 1825);
FORCEPROP 1 LAST PATH I136
J 2
(5700 1755);
DISPLAY 0.723404 (5700 1755);
PAINT GREEN (5700 1755);
DISPLAY INVISIBLE (5700 1755);
FORCEPROP 1 LAST NEEDS_NO_SIZE TRUE
J 2
(5775 1700);
DISPLAY 0.468085 (5775 1700);
PAINT GREEN (5775 1700);
DISPLAY INVISIBLE (5775 1700);
FORCEPROP 2 LAST CDS_LIB pure_quanta
J 0
(5775 1700);
DISPLAY INVISIBLE (5775 1700);
FORCEADD UNIVERSAL_GND..1
(1425 3825);
FORCEPROP 3 LASTPIN (1425 3875) SIG_NAME GND\g
J 0
(1435 3885);
DISPLAY 0.659574 (1435 3885);
PAINT MONO (1435 3885);
DISPLAY INVISIBLE (1435 3885);
FORCEPROP 2 LAST CDS_LIB pure_quanta_power
J 0
(1425 3825);
PAINT MONO (1425 3825);
DISPLAY INVISIBLE (1425 3825);
FORCEPROP 1 LAST PATH I20
J 0
(1500 3825);
DISPLAY 0.872340 (1500 3825);
PAINT AQUA (1500 3825);
DISPLAY INVISIBLE (1500 3825);
FORCEPROP 1 LAST HDL_POWER GND
J 1
(1450 3750);
DISPLAY 0.872340 (1450 3750);
PAINT GREEN (1450 3750);
DISPLAY INVISIBLE (1450 3750);
FORCEADD Q_RES..2
R 2
(1425 4050);
FORCEPROP 1 LAST LOCATION PR270
J 2
(1380 4175);
DISPLAY 0.489362 (1380 4175);
PAINT SKYBLUE (1380 4175);
FORCEPROP 0 LAST $SEC 1
J 0
(1400 4225);
DISPLAY 0.680851 (1400 4225);
PAINT MONO (1400 4225);
DISPLAY INVISIBLE (1400 4225);
FORCEPROP 0 LAST CDS_SEC 1
J 0
(1400 4225);
DISPLAY 1.021277 (1400 4225);
DISPLAY INVISIBLE (1400 4225);
FORCEPROP 1 LASTPIN (1425 4150) $PN 1
J 2
(1420 4112);
DISPLAY 0.489362 (1420 4112);
PAINT MONO (1420 4112);
FORCEPROP 1 LASTPIN (1425 3950) $PN 2
J 2
(1420 3960);
DISPLAY 0.489362 (1420 3960);
PAINT MONO (1420 3960);
FORCEPROP 1 LAST WATTAGE 1/16W
J 2
(1385 4025);
DISPLAY 0.489362 (1385 4025);
PAINT SKYBLUE (1385 4025);
FORCEPROP 1 LAST MATERIAL EMPTY
J 2
(1385 3975);
DISPLAY 0.489362 (1385 3975);
PAINT RED (1385 3975);
FORCEPROP 1 LAST TOLERANCE 1%
J 2
(1380 4075);
DISPLAY 0.489362 (1380 4075);
PAINT SKYBLUE (1380 4075);
FORCEPROP 1 LAST VALUE 8.87K
J 2
(1380 4125);
DISPLAY 0.489362 (1380 4125);
PAINT SKYBLUE (1380 4125);
FORCEPROP 1 LAST PART_NUMBER CS28872FB01
J 2
(1385 3925);
DISPLAY 0.489362 (1385 3925);
PAINT SKYBLUE (1385 3925);
FORCEPROP 1 LAST PACK_TYPE 0402LF
J 2
(1385 3875);
DISPLAY 0.489362 (1385 3875);
PAINT SKYBLUE (1385 3875);
FORCEPROP 2 LAST CDS_LIB pure_quanta
J 2
(1425 4050);
DISPLAY INVISIBLE (1425 4050);
FORCEPROP 1 LAST PATH I21
J 2
(1375 4225);
DISPLAY 0.978723 (1375 4225);
PAINT WHITE (1375 4225);
DISPLAY INVISIBLE (1375 4225);
FORCEADD OFFPAGE..1
(1900 3950);
FORCEPROP 2 LAST $XR0 193 
J 0
(1648 3950);
DISPLAY 0.638298 (1648 3950);
PAINT MONO (1648 3950);
FORCEPROP 2 LAST PATH I23
J 0
(1475 4000);
DISPLAY 1.021277 (1475 4000);
DISPLAY INVISIBLE (1475 4000);
FORCEPROP 1 LAST COMMENT_BODY TRUE
J 0
(2025 3850);
DISPLAY 0.872340 (2025 3850);
PAINT GREEN (2025 3850);
DISPLAY INVISIBLE (2025 3850);
FORCEPROP 1 LAST OFFPAGE TRUE
J 0
(2225 3825);
DISPLAY 0.872340 (2225 3825);
PAINT GREEN (2225 3825);
DISPLAY INVISIBLE (2225 3825);
FORCEPROP 2 LAST CDS_LIB standard
J 0
(1900 3950);
DISPLAY INVISIBLE (1900 3950);
FORCEADD OFFPAGE..5
(1900 4050);
FORCEPROP 2 LAST $XR3 193 
J 0
(1615 4122);
DISPLAY 0.638298 (1615 4122);
PAINT MONO (1615 4122);
FORCEPROP 2 LAST $XR2 196 
J 0
(1615 4086);
DISPLAY 0.638298 (1615 4086);
PAINT MONO (1615 4086);
FORCEPROP 2 LAST $XR1 195 
J 0
(1615 4014);
DISPLAY 0.638298 (1615 4014);
PAINT MONO (1615 4014);
FORCEPROP 2 LAST $XR0 194 
J 0
(1615 4050);
DISPLAY 0.638298 (1615 4050);
PAINT MONO (1615 4050);
FORCEPROP 2 LAST PATH I25
J 0
(1625 4200);
DISPLAY 1.021277 (1625 4200);
DISPLAY INVISIBLE (1625 4200);
FORCEPROP 1 LAST COMMENT_BODY TRUE
J 0
(2000 3975);
DISPLAY 0.872340 (2000 3975);
PAINT GREEN (2000 3975);
DISPLAY INVISIBLE (2000 3975);
FORCEPROP 1 LAST OFFPAGE TRUE
J 0
(2225 3925);
DISPLAY 0.872340 (2225 3925);
PAINT GREEN (2225 3925);
DISPLAY INVISIBLE (2225 3925);
FORCEPROP 2 LAST CDS_LIB standard
J 0
(1900 4050);
DISPLAY INVISIBLE (1900 4050);
FORCEADD OFFPAGE..1
(1900 4450);
FORCEPROP 2 LAST $XR5 199 
J 0
(1048 4450);
DISPLAY 0.638298 (1048 4450);
PAINT MONO (1048 4450);
FORCEPROP 2 LAST $XR4 198 
J 0
(1168 4450);
DISPLAY 0.638298 (1168 4450);
PAINT MONO (1168 4450);
FORCEPROP 2 LAST $XR3 196 
J 0
(1288 4450);
DISPLAY 0.638298 (1288 4450);
PAINT MONO (1288 4450);
FORCEPROP 2 LAST $XR2 195 
J 0
(1408 4450);
DISPLAY 0.638298 (1408 4450);
PAINT MONO (1408 4450);
FORCEPROP 2 LAST $XR1 194 
J 0
(1528 4450);
DISPLAY 0.638298 (1528 4450);
PAINT MONO (1528 4450);
FORCEPROP 2 LAST $XR0 193 
J 0
(1648 4450);
DISPLAY 0.638298 (1648 4450);
PAINT MONO (1648 4450);
FORCEPROP 2 LAST PATH I26
J 0
(1650 4500);
DISPLAY 1.021277 (1650 4500);
DISPLAY INVISIBLE (1650 4500);
FORCEPROP 1 LAST COMMENT_BODY TRUE
J 0
(2025 4350);
DISPLAY 0.872340 (2025 4350);
PAINT GREEN (2025 4350);
DISPLAY INVISIBLE (2025 4350);
FORCEPROP 1 LAST OFFPAGE TRUE
J 0
(2225 4325);
DISPLAY 0.872340 (2225 4325);
PAINT GREEN (2225 4325);
DISPLAY INVISIBLE (2225 4325);
FORCEPROP 2 LAST CDS_LIB standard
J 0
(1900 4450);
DISPLAY INVISIBLE (1900 4450);
FORCEADD OFFPAGE..5
(1900 4550);
FORCEPROP 2 LAST $XR0 193 
J 0
(1615 4550);
DISPLAY 0.638298 (1615 4550);
PAINT MONO (1615 4550);
FORCEPROP 2 LAST PATH I28
J 0
(1625 4600);
DISPLAY 1.021277 (1625 4600);
DISPLAY INVISIBLE (1625 4600);
FORCEPROP 1 LAST COMMENT_BODY TRUE
J 0
(2000 4475);
DISPLAY 0.872340 (2000 4475);
PAINT GREEN (2000 4475);
DISPLAY INVISIBLE (2000 4475);
FORCEPROP 1 LAST OFFPAGE TRUE
J 0
(2225 4425);
DISPLAY 0.872340 (2225 4425);
PAINT GREEN (2225 4425);
DISPLAY INVISIBLE (2225 4425);
FORCEPROP 2 LAST CDS_LIB standard
J 0
(1900 4550);
DISPLAY INVISIBLE (1900 4550);
FORCEADD ISL99390FRZTR5935..1
(3350 4550);
FORCEPROP 1 LAST LOCATION PU38
J 0
(3050 5425);
DISPLAY 0.489362 (3050 5425);
PAINT SKYBLUE (3050 5425);
FORCEPROP 2 LAST $SEC 1
J 0
(3050 5600);
DISPLAY 0.680851 (3050 5600);
PAINT MONO (3050 5600);
DISPLAY INVISIBLE (3050 5600);
FORCEPROP 2 LAST CDS_SEC 1
J 0
(3050 5600);
DISPLAY 1.021277 (3050 5600);
DISPLAY INVISIBLE (3050 5600);
FORCEPROP 2 LASTPIN (3750 4100) $PN 2
J 0
(3760 4110);
DISPLAY 0.489362 (3760 4110);
PAINT MONO (3760 4110);
FORCEPROP 2 LASTPIN (3750 4900) $PN 33
J 0
(3760 4910);
DISPLAY 0.489362 (3760 4910);
PAINT MONO (3760 4910);
FORCEPROP 2 LASTPIN (2900 4300) $PN 31
J 2
(2890 4310);
DISPLAY 0.489362 (2890 4310);
PAINT MONO (2890 4310);
FORCEPROP 2 LASTPIN (2900 4700) $PN 35
J 2
(2890 4710);
DISPLAY 0.489362 (2890 4710);
PAINT MONO (2890 4710);
FORCEPROP 2 LASTPIN (3750 4250) $PN 6
J 0
(3760 4260);
DISPLAY 0.489362 (3760 4260);
PAINT MONO (3760 4260);
FORCEPROP 2 LASTPIN (3750 4200) $PN 41
J 0
(3760 4210);
DISPLAY 0.489362 (3760 4210);
PAINT MONO (3760 4210);
FORCEPROP 2 LASTPIN (2900 4550) $PN 38
J 2
(2890 4560);
DISPLAY 0.489362 (2890 4560);
PAINT MONO (2890 4560);
FORCEPROP 2 LASTPIN (2900 4250) $PN 37
J 2
(2890 4260);
DISPLAY 0.489362 (2890 4260);
PAINT MONO (2890 4260);
FORCEPROP 2 LASTPIN (3750 4050) $PN 5
J 0
(3760 4060);
DISPLAY 0.489362 (3760 4060);
PAINT MONO (3760 4060);
FORCEPROP 2 LASTPIN (3750 4000) $PN 7_9-20_24
J 0
(3760 4010);
DISPLAY 0.489362 (3760 4010);
PAINT MONO (3760 4010);
FORCEPROP 2 LASTPIN (3750 3950) $PN 40
J 0
(3760 3960);
DISPLAY 0.489362 (3760 3960);
PAINT MONO (3760 3960);
FORCEPROP 2 LASTPIN (3750 4650) $PN 32
J 0
(3760 4660);
DISPLAY 0.489362 (3760 4660);
PAINT MONO (3760 4660);
FORCEPROP 2 LASTPIN (2900 5200) $PN 4
J 2
(2890 5210);
DISPLAY 0.489362 (2890 5210);
PAINT MONO (2890 5210);
FORCEPROP 2 LASTPIN (2900 3950) $PN 34
J 2
(2890 3960);
DISPLAY 0.489362 (2890 3960);
PAINT MONO (2890 3960);
FORCEPROP 2 LASTPIN (2900 4450) $PN 39
J 2
(2890 4460);
DISPLAY 0.489362 (2890 4460);
PAINT MONO (2890 4460);
FORCEPROP 2 LASTPIN (3750 4550) $PN 10_19
J 0
(3760 4560);
DISPLAY 0.489362 (3760 4560);
PAINT MONO (3760 4560);
FORCEPROP 2 LASTPIN (2900 4050) $PN 36
J 2
(2890 4060);
DISPLAY 0.489362 (2890 4060);
PAINT MONO (2890 4060);
FORCEPROP 2 LASTPIN (2900 4900) $PN 3
J 2
(2890 4910);
DISPLAY 0.489362 (2890 4910);
PAINT MONO (2890 4910);
FORCEPROP 2 LASTPIN (3750 5200) $PN 25_29
J 0
(3760 5210);
DISPLAY 0.489362 (3760 5210);
PAINT MONO (3760 5210);
FORCEPROP 2 LASTPIN (3750 5150) $PN 30
J 0
(3760 5160);
DISPLAY 0.489362 (3760 5160);
PAINT MONO (3760 5160);
FORCEPROP 2 LASTPIN (3750 4300) $PN 1
J 0
(3760 4310);
DISPLAY 0.489362 (3760 4310);
PAINT MONO (3760 4310);
FORCEPROP 2 LAST PART_TYPE SMLF
J 0
(3050 5575);
DISPLAY 0.638298 (3050 5575);
FORCEPROP 1 LAST MATERIAL IC
J 0
(3050 5275);
DISPLAY 0.489362 (3050 5275);
PAINT SKYBLUE (3050 5275);
FORCEPROP 2 LAST VALUE ISL99390FRZ-TR5935
J 0
(3050 5525);
DISPLAY 0.489362 (3050 5525);
PAINT SKYBLUE (3050 5525);
FORCEPROP 1 LAST PART_NUMBER AL099390004
J 0
(3050 5350);
DISPLAY 0.489362 (3050 5350);
PAINT SKYBLUE (3050 5350);
FORCEPROP 1 LAST NEEDS_NO_SIZE TRUE
J 0
(3350 4550);
DISPLAY 0.723404 (3350 4550);
PAINT GREEN (3350 4550);
DISPLAY INVISIBLE (3350 4550);
FORCEPROP 1 LAST CDS_LMAN_SYM_OUTLINE -300,700,250,-650
J 0
(3350 4550);
DISPLAY 0.468085 (3350 4550);
PAINT GREEN (3350 4550);
DISPLAY INVISIBLE (3350 4550);
FORCEPROP 2 LAST CDS_LIB pure_quanta
J 0
(3350 4550);
DISPLAY INVISIBLE (3350 4550);
FORCEPROP 1 LAST PATH I31
J 0
(3350 4550);
DISPLAY 0.723404 (3350 4550);
PAINT GREEN (3350 4550);
DISPLAY INVISIBLE (3350 4550);
FORCEADD UNIVERSAL_GND..1
(4000 3825);
FORCEPROP 3 LASTPIN (4000 3875) SIG_NAME GND\g
J 0
(4010 3885);
DISPLAY 0.659574 (4010 3885);
PAINT MONO (4010 3885);
DISPLAY INVISIBLE (4010 3885);
FORCEPROP 2 LAST CDS_LIB pure_quanta_power
J 0
(4000 3825);
PAINT MONO (4000 3825);
DISPLAY INVISIBLE (4000 3825);
FORCEPROP 1 LAST PATH I36
J 0
(4075 3825);
DISPLAY 0.872340 (4075 3825);
PAINT AQUA (4075 3825);
DISPLAY INVISIBLE (4075 3825);
FORCEPROP 1 LAST HDL_POWER GND
J 1
(4025 3750);
DISPLAY 0.872340 (4025 3750);
PAINT GREEN (4025 3750);
DISPLAY INVISIBLE (4025 3750);
FORCEADD Q_CAP..1
(4625 5450);
FORCEPROP 1 LAST LOCATION PC425_5
J 0
(4675 5600);
DISPLAY 0.489362 (4675 5600);
PAINT SKYBLUE (4675 5600);
FORCEPROP 0 LAST $SEC 1
J 0
(4675 5650);
DISPLAY 0.680851 (4675 5650);
PAINT MONO (4675 5650);
DISPLAY INVISIBLE (4675 5650);
FORCEPROP 0 LAST CDS_SEC 1
J 0
(4675 5650);
DISPLAY 1.021277 (4675 5650);
DISPLAY INVISIBLE (4675 5650);
FORCEPROP 1 LASTPIN (4625 5550) $PN 1
J 0
(4635 5530);
DISPLAY 0.489362 (4635 5530);
PAINT MONO (4635 5530);
FORCEPROP 1 LASTPIN (4625 5350) $PN 2
J 0
(4635 5330);
DISPLAY 0.489362 (4635 5330);
PAINT MONO (4635 5330);
FORCEPROP 1 LAST MATERIAL X6S
J 0
(4675 5400);
DISPLAY 0.489362 (4675 5400);
PAINT SKYBLUE (4675 5400);
FORCEPROP 1 LAST TOLERANCE 10%
J 0
(4675 5450);
DISPLAY 0.489362 (4675 5450);
PAINT SKYBLUE (4675 5450);
FORCEPROP 1 LAST VALUE 1UF
J 0
(4675 5550);
DISPLAY 0.489362 (4675 5550);
PAINT SKYBLUE (4675 5550);
FORCEPROP 1 LAST PART_NUMBER CH5104KEB02
J 0
(4675 5300);
DISPLAY 0.489362 (4675 5300);
PAINT SKYBLUE (4675 5300);
FORCEPROP 1 LAST VOLTAGE 25V
J 0
(4675 5500);
DISPLAY 0.489362 (4675 5500);
PAINT SKYBLUE (4675 5500);
FORCEPROP 1 LAST PACK_TYPE C0402
J 0
(4675 5350);
DISPLAY 0.489362 (4675 5350);
PAINT SKYBLUE (4675 5350);
FORCEPROP 2 LAST CDS_LIB pure_quanta
J 0
(4625 5450);
DISPLAY INVISIBLE (4625 5450);
FORCEPROP 1 LAST PATH I39
J 0
(4675 5600);
DISPLAY 0.978723 (4675 5600);
PAINT WHITE (4675 5600);
DISPLAY INVISIBLE (4675 5600);
FORCEADD Q_CAP..1
(5025 5450);
FORCEPROP 1 LAST LOCATION PC426_5
J 0
(5075 5600);
DISPLAY 0.489362 (5075 5600);
PAINT SKYBLUE (5075 5600);
FORCEPROP 0 LAST $SEC 1
J 0
(5075 5650);
DISPLAY 0.680851 (5075 5650);
PAINT MONO (5075 5650);
DISPLAY INVISIBLE (5075 5650);
FORCEPROP 0 LAST CDS_SEC 1
J 0
(5075 5650);
DISPLAY 1.021277 (5075 5650);
DISPLAY INVISIBLE (5075 5650);
FORCEPROP 1 LASTPIN (5025 5550) $PN 1
J 0
(5035 5530);
DISPLAY 0.489362 (5035 5530);
PAINT MONO (5035 5530);
FORCEPROP 1 LASTPIN (5025 5350) $PN 2
J 0
(5035 5330);
DISPLAY 0.489362 (5035 5330);
PAINT MONO (5035 5330);
FORCEPROP 1 LAST MATERIAL X6S
J 0
(5075 5400);
DISPLAY 0.489362 (5075 5400);
PAINT SKYBLUE (5075 5400);
FORCEPROP 1 LAST TOLERANCE 10%
J 0
(5075 5450);
DISPLAY 0.489362 (5075 5450);
PAINT SKYBLUE (5075 5450);
FORCEPROP 1 LAST VALUE 10UF
J 0
(5075 5550);
DISPLAY 0.489362 (5075 5550);
PAINT SKYBLUE (5075 5550);
FORCEPROP 1 LAST PART_NUMBER CH6104KEA00
J 0
(5075 5300);
DISPLAY 0.489362 (5075 5300);
PAINT SKYBLUE (5075 5300);
FORCEPROP 1 LAST VOLTAGE 25V
J 0
(5075 5500);
DISPLAY 0.489362 (5075 5500);
PAINT SKYBLUE (5075 5500);
FORCEPROP 1 LAST PACK_TYPE C0805
J 0
(5075 5350);
DISPLAY 0.489362 (5075 5350);
PAINT SKYBLUE (5075 5350);
FORCEPROP 2 LAST CDS_LIB pure_quanta
J 0
(5025 5450);
DISPLAY INVISIBLE (5025 5450);
FORCEPROP 1 LAST PATH I40
J 0
(5075 5600);
DISPLAY 0.978723 (5075 5600);
PAINT WHITE (5075 5600);
DISPLAY INVISIBLE (5075 5600);
FORCEADD UNIVERSAL_GND..1
(5800 5100);
FORCEPROP 3 LASTPIN (5800 5150) SIG_NAME GND\g
J 0
(5810 5160);
DISPLAY 0.659574 (5810 5160);
PAINT MONO (5810 5160);
DISPLAY INVISIBLE (5810 5160);
FORCEPROP 2 LAST CDS_LIB pure_quanta_power
J 0
(5800 5100);
PAINT MONO (5800 5100);
DISPLAY INVISIBLE (5800 5100);
FORCEPROP 1 LAST PATH I54
J 0
(5875 5100);
DISPLAY 0.872340 (5875 5100);
PAINT AQUA (5875 5100);
DISPLAY INVISIBLE (5875 5100);
FORCEPROP 1 LAST HDL_POWER GND
J 1
(5825 5025);
DISPLAY 0.872340 (5825 5025);
PAINT GREEN (5825 5025);
DISPLAY INVISIBLE (5825 5025);
FORCEADD Q_CAP..1
(5425 5450);
FORCEPROP 1 LAST LOCATION PC427_5
J 0
(5475 5600);
DISPLAY 0.489362 (5475 5600);
PAINT SKYBLUE (5475 5600);
FORCEPROP 0 LAST $SEC 1
J 0
(5475 5650);
DISPLAY 0.680851 (5475 5650);
PAINT MONO (5475 5650);
DISPLAY INVISIBLE (5475 5650);
FORCEPROP 0 LAST CDS_SEC 1
J 0
(5475 5650);
DISPLAY 1.021277 (5475 5650);
DISPLAY INVISIBLE (5475 5650);
FORCEPROP 1 LASTPIN (5425 5550) $PN 1
J 0
(5435 5530);
DISPLAY 0.489362 (5435 5530);
PAINT MONO (5435 5530);
FORCEPROP 1 LASTPIN (5425 5350) $PN 2
J 0
(5435 5330);
DISPLAY 0.489362 (5435 5330);
PAINT MONO (5435 5330);
FORCEPROP 1 LAST MATERIAL X6S
J 0
(5475 5400);
DISPLAY 0.489362 (5475 5400);
PAINT SKYBLUE (5475 5400);
FORCEPROP 1 LAST TOLERANCE 10%
J 0
(5475 5450);
DISPLAY 0.489362 (5475 5450);
PAINT SKYBLUE (5475 5450);
FORCEPROP 1 LAST VALUE 10UF
J 0
(5475 5550);
DISPLAY 0.489362 (5475 5550);
PAINT SKYBLUE (5475 5550);
FORCEPROP 1 LAST PART_NUMBER CH6104KEA00
J 0
(5475 5300);
DISPLAY 0.489362 (5475 5300);
PAINT SKYBLUE (5475 5300);
FORCEPROP 1 LAST VOLTAGE 25V
J 0
(5475 5500);
DISPLAY 0.489362 (5475 5500);
PAINT SKYBLUE (5475 5500);
FORCEPROP 1 LAST PACK_TYPE C0805
J 0
(5475 5350);
DISPLAY 0.489362 (5475 5350);
PAINT SKYBLUE (5475 5350);
FORCEPROP 2 LAST CDS_LIB pure_quanta
J 0
(5425 5450);
DISPLAY INVISIBLE (5425 5450);
FORCEPROP 1 LAST PATH I59
J 0
(5475 5600);
DISPLAY 0.978723 (5475 5600);
PAINT WHITE (5475 5600);
DISPLAY INVISIBLE (5475 5600);
FORCEADD Q_CAP..1
(5800 5450);
FORCEPROP 1 LAST LOCATION PC429_5
J 0
(5850 5600);
DISPLAY 0.489362 (5850 5600);
PAINT SKYBLUE (5850 5600);
FORCEPROP 0 LAST $SEC 1
J 0
(5850 5650);
DISPLAY 0.680851 (5850 5650);
PAINT MONO (5850 5650);
DISPLAY INVISIBLE (5850 5650);
FORCEPROP 0 LAST CDS_SEC 1
J 0
(5850 5650);
DISPLAY 1.021277 (5850 5650);
DISPLAY INVISIBLE (5850 5650);
FORCEPROP 1 LASTPIN (5800 5550) $PN 1
J 0
(5810 5530);
DISPLAY 0.489362 (5810 5530);
PAINT MONO (5810 5530);
FORCEPROP 1 LASTPIN (5800 5350) $PN 2
J 0
(5810 5330);
DISPLAY 0.489362 (5810 5330);
PAINT MONO (5810 5330);
FORCEPROP 1 LAST MATERIAL X6S
J 0
(5850 5400);
DISPLAY 0.489362 (5850 5400);
PAINT SKYBLUE (5850 5400);
FORCEPROP 1 LAST TOLERANCE 10%
J 0
(5850 5450);
DISPLAY 0.489362 (5850 5450);
PAINT SKYBLUE (5850 5450);
FORCEPROP 1 LAST VALUE 10UF
J 0
(5850 5550);
DISPLAY 0.489362 (5850 5550);
PAINT SKYBLUE (5850 5550);
FORCEPROP 1 LAST PART_NUMBER CH6104KEA00
J 0
(5850 5300);
DISPLAY 0.489362 (5850 5300);
PAINT SKYBLUE (5850 5300);
FORCEPROP 1 LAST VOLTAGE 25V
J 0
(5850 5500);
DISPLAY 0.489362 (5850 5500);
PAINT SKYBLUE (5850 5500);
FORCEPROP 1 LAST PACK_TYPE C0805
J 0
(5850 5350);
DISPLAY 0.489362 (5850 5350);
PAINT SKYBLUE (5850 5350);
FORCEPROP 2 LAST CDS_LIB pure_quanta
J 0
(5800 5450);
DISPLAY INVISIBLE (5800 5450);
FORCEPROP 1 LAST PATH I60
J 0
(5850 5600);
DISPLAY 0.978723 (5850 5600);
PAINT WHITE (5850 5600);
DISPLAY INVISIBLE (5850 5600);
FORCEADD VCC_CORE..1
(5800 5800);
FORCEPROP 3 LASTPIN (5800 5750) SIG_NAME SW_P12V_STBY_PVDDCR_CPU1_P1_FLT\g
J 0
(5810 5760);
DISPLAY 0.659574 (5810 5760);
PAINT MONO (5810 5760);
DISPLAY INVISIBLE (5810 5760);
FORCEPROP 1 LAST HDL_POWER SW_P12V_STBY_PVDDCR_CPU1_P1_FLT
J 1
(5800 5850);
DISPLAY 0.489362 (5800 5850);
PAINT GREEN (5800 5850);
FORCEPROP 2 LAST CDS_LIB pure_quanta_power
J 0
(5800 5800);
DISPLAY INVISIBLE (5800 5800);
FORCEPROP 1 LAST PATH I61
J 0
(5850 5825);
DISPLAY 0.872340 (5850 5825);
PAINT AQUA (5850 5825);
DISPLAY INVISIBLE (5850 5825);
FORCEADD OFFPAGE..3
(7825 4300);
FORCEPROP 2 LAST $XR0 194 
J 0
(8129 4300);
DISPLAY 0.638298 (8129 4300);
PAINT MONO (8129 4300);
FORCEPROP 2 LAST PATH I73
J 0
(8025 4375);
DISPLAY 1.021277 (8025 4375);
DISPLAY INVISIBLE (8025 4375);
FORCEPROP 1 LAST COMMENT_BODY TRUE
J 0
(7775 4200);
DISPLAY 0.872340 (7775 4200);
PAINT GREEN (7775 4200);
DISPLAY INVISIBLE (7775 4200);
FORCEPROP 1 LAST OFFPAGE TRUE
J 0
(8150 4175);
DISPLAY 0.872340 (8150 4175);
PAINT GREEN (8150 4175);
DISPLAY INVISIBLE (8150 4175);
FORCEPROP 2 LAST CDS_LIB standard
J 0
(7825 4300);
DISPLAY INVISIBLE (7825 4300);
FORCEADD OFFPAGE..6
(5850 4300);
FORCEPROP 2 LAST $XR0 196 
J 0
(5540 4300);
DISPLAY 0.638298 (5540 4300);
PAINT MONO (5540 4300);
FORCEPROP 2 LAST PATH I75
J 0
(5900 4375);
DISPLAY 1.021277 (5900 4375);
DISPLAY INVISIBLE (5900 4375);
FORCEPROP 1 LAST COMMENT_BODY TRUE
J 0
(5950 4225);
DISPLAY 0.872340 (5950 4225);
PAINT GREEN (5950 4225);
DISPLAY INVISIBLE (5950 4225);
FORCEPROP 1 LAST OFFPAGE TRUE
J 0
(6175 4175);
DISPLAY 0.872340 (6175 4175);
PAINT GREEN (6175 4175);
DISPLAY INVISIBLE (6175 4175);
FORCEPROP 2 LAST CDS_LIB standard
J 0
(5850 4300);
DISPLAY INVISIBLE (5850 4300);
FORCEADD Q_RES..1
(5775 3500);
FORCEPROP 1 LAST LOCATION PR273
J 0
(5725 3525);
DISPLAY 0.489362 (5725 3525);
PAINT SKYBLUE (5725 3525);
FORCEPROP 0 LAST $SEC 1
J 0
(6025 3650);
DISPLAY 0.680851 (6025 3650);
PAINT MONO (6025 3650);
DISPLAY INVISIBLE (6025 3650);
FORCEPROP 0 LAST CDS_SEC 1
J 0
(6025 3650);
DISPLAY 1.021277 (6025 3650);
DISPLAY INVISIBLE (6025 3650);
FORCEPROP 1 LASTPIN (5675 3500) $PN 1
J 0
(5687 3512);
DISPLAY 0.489362 (5687 3512);
PAINT MONO (5687 3512);
FORCEPROP 1 LASTPIN (5875 3500) $PN 2
J 0
(5837 3512);
DISPLAY 0.489362 (5837 3512);
PAINT MONO (5837 3512);
FORCEPROP 1 LAST WATTAGE 1/16W
J 2
(6000 3575);
DISPLAY 0.489362 (6000 3575);
PAINT SKYBLUE (6000 3575);
FORCEPROP 1 LAST MATERIAL CHIP
J 0
(5900 3525);
DISPLAY 0.489362 (5900 3525);
PAINT SKYBLUE (5900 3525);
FORCEPROP 1 LAST TOLERANCE 5%
J 0
(5625 3525);
DISPLAY 0.489362 (5625 3525);
PAINT SKYBLUE (5625 3525);
FORCEPROP 1 LAST VALUE 0
J 2
(5600 3525);
DISPLAY 0.489362 (5600 3525);
PAINT SKYBLUE (5600 3525);
FORCEPROP 1 LAST PART_NUMBER CS00002JB38
J 0
(5500 3450);
DISPLAY 0.489362 (5500 3450);
PAINT SKYBLUE (5500 3450);
FORCEPROP 1 LAST PACK_TYPE 0402LF
J 0
(5875 3450);
DISPLAY 0.489362 (5875 3450);
PAINT SKYBLUE (5875 3450);
FORCEPROP 2 LAST CDS_LIB pure_quanta
J 0
(5775 3500);
DISPLAY INVISIBLE (5775 3500);
FORCEPROP 1 LAST PATH I76
J 0
(5725 3650);
DISPLAY 0.978723 (5725 3650);
PAINT WHITE (5725 3650);
DISPLAY INVISIBLE (5725 3650);
FORCEADD VCC_CORE..1
(8725 4700);
FORCEPROP 3 LASTPIN (8725 4650) SIG_NAME PVDDCR_CPU1_P1\g
J 0
(8735 4660);
DISPLAY 0.659574 (8735 4660);
PAINT MONO (8735 4660);
DISPLAY INVISIBLE (8735 4660);
FORCEPROP 1 LAST HDL_POWER PVDDCR_CPU1_P1
J 1
(8725 4750);
DISPLAY 0.489362 (8725 4750);
PAINT GREEN (8725 4750);
FORCEPROP 2 LAST CDS_LIB pure_quanta_power
J 0
(8725 4700);
DISPLAY INVISIBLE (8725 4700);
FORCEPROP 1 LAST PATH I77
J 0
(8775 4725);
DISPLAY 0.872340 (8775 4725);
PAINT AQUA (8775 4725);
DISPLAY INVISIBLE (8775 4725);
FORCEADD UNIVERSAL_GND..1
(8725 4000);
FORCEPROP 3 LASTPIN (8725 4050) SIG_NAME GND\g
J 0
(8735 4060);
DISPLAY 0.659574 (8735 4060);
PAINT MONO (8735 4060);
DISPLAY INVISIBLE (8735 4060);
FORCEPROP 2 LAST CDS_LIB pure_quanta_power
J 0
(8725 4000);
PAINT MONO (8725 4000);
DISPLAY INVISIBLE (8725 4000);
FORCEPROP 1 LAST PATH I78
J 0
(8800 4000);
DISPLAY 0.872340 (8800 4000);
PAINT AQUA (8800 4000);
DISPLAY INVISIBLE (8800 4000);
FORCEPROP 1 LAST HDL_POWER GND
J 1
(8750 3925);
DISPLAY 0.872340 (8750 3925);
PAINT GREEN (8750 3925);
DISPLAY INVISIBLE (8750 3925);
FORCEADD Q_CAP..1
(8725 4350);
FORCEPROP 1 LAST LOCATION PC431_5
J 0
(8775 4475);
DISPLAY 0.489362 (8775 4475);
PAINT SKYBLUE (8775 4475);
FORCEPROP 0 LAST $SEC 1
J 0
(8775 4525);
DISPLAY 0.680851 (8775 4525);
PAINT MONO (8775 4525);
DISPLAY INVISIBLE (8775 4525);
FORCEPROP 0 LAST CDS_SEC 1
J 0
(8775 4525);
DISPLAY 1.021277 (8775 4525);
DISPLAY INVISIBLE (8775 4525);
FORCEPROP 1 LASTPIN (8725 4450) $PN 1
J 0
(8735 4430);
DISPLAY 0.489362 (8735 4430);
PAINT MONO (8735 4430);
FORCEPROP 1 LASTPIN (8725 4250) $PN 2
J 0
(8735 4230);
DISPLAY 0.489362 (8735 4230);
PAINT MONO (8735 4230);
FORCEPROP 1 LAST MATERIAL X6S
J 0
(8775 4275);
DISPLAY 0.489362 (8775 4275);
PAINT SKYBLUE (8775 4275);
FORCEPROP 1 LAST TOLERANCE 20%
J 0
(8775 4325);
DISPLAY 0.489362 (8775 4325);
PAINT SKYBLUE (8775 4325);
FORCEPROP 1 LAST VALUE 22UF
J 0
(8775 4425);
DISPLAY 0.489362 (8775 4425);
PAINT SKYBLUE (8775 4425);
FORCEPROP 1 LAST PART_NUMBER TMP_QCH622KMEA01
J 0
(8775 4175);
DISPLAY 0.489362 (8775 4175);
PAINT SKYBLUE (8775 4175);
FORCEPROP 1 LAST VOLTAGE 4V
J 0
(8775 4375);
DISPLAY 0.489362 (8775 4375);
PAINT SKYBLUE (8775 4375);
FORCEPROP 1 LAST PACK_TYPE 0805
J 0
(8775 4225);
DISPLAY 0.489362 (8775 4225);
PAINT SKYBLUE (8775 4225);
FORCEPROP 2 LAST CDS_LIB pure_quanta
J 0
(8725 4350);
DISPLAY INVISIBLE (8725 4350);
FORCEPROP 1 LAST PATH I79
J 0
(8775 4500);
DISPLAY 0.978723 (8775 4500);
PAINT WHITE (8775 4500);
DISPLAY INVISIBLE (8775 4500);
FORCEADD Q_CAP..1
(8300 4350);
FORCEPROP 1 LAST LOCATION PC430_5
J 0
(8350 4475);
DISPLAY 0.489362 (8350 4475);
PAINT SKYBLUE (8350 4475);
FORCEPROP 0 LAST $SEC 1
J 0
(8350 4525);
DISPLAY 0.680851 (8350 4525);
PAINT MONO (8350 4525);
DISPLAY INVISIBLE (8350 4525);
FORCEPROP 0 LAST CDS_SEC 1
J 0
(8350 4525);
DISPLAY 1.021277 (8350 4525);
DISPLAY INVISIBLE (8350 4525);
FORCEPROP 1 LASTPIN (8300 4450) $PN 1
J 0
(8310 4430);
DISPLAY 0.489362 (8310 4430);
PAINT MONO (8310 4430);
FORCEPROP 1 LASTPIN (8300 4250) $PN 2
J 0
(8310 4230);
DISPLAY 0.489362 (8310 4230);
PAINT MONO (8310 4230);
FORCEPROP 1 LAST MATERIAL X6S
J 0
(8350 4275);
DISPLAY 0.489362 (8350 4275);
PAINT SKYBLUE (8350 4275);
FORCEPROP 1 LAST TOLERANCE 20%
J 0
(8350 4325);
DISPLAY 0.489362 (8350 4325);
PAINT SKYBLUE (8350 4325);
FORCEPROP 1 LAST VALUE 22UF
J 0
(8350 4425);
DISPLAY 0.489362 (8350 4425);
PAINT SKYBLUE (8350 4425);
FORCEPROP 1 LAST PART_NUMBER TMP_QCH622KMEA01
J 0
(8350 4175);
DISPLAY 0.489362 (8350 4175);
PAINT SKYBLUE (8350 4175);
FORCEPROP 1 LAST VOLTAGE 4V
J 0
(8350 4375);
DISPLAY 0.489362 (8350 4375);
PAINT SKYBLUE (8350 4375);
FORCEPROP 1 LAST PACK_TYPE 0805
J 0
(8350 4225);
DISPLAY 0.489362 (8350 4225);
PAINT SKYBLUE (8350 4225);
FORCEPROP 2 LAST CDS_LIB pure_quanta
J 0
(8300 4350);
DISPLAY INVISIBLE (8300 4350);
FORCEPROP 1 LAST PATH I80
J 0
(8350 4500);
DISPLAY 0.978723 (8350 4500);
PAINT WHITE (8350 4500);
DISPLAY INVISIBLE (8350 4500);
FORCEADD Q_INDUCTOR4P_14..1
(6800 4425);
FORCEPROP 1 LAST LOCATION PL45
J 0
(6575 4680);
DISPLAY 0.489362 (6575 4680);
PAINT SKYBLUE (6575 4680);
FORCEPROP 0 LAST $SEC 1
J 0
(6575 4725);
DISPLAY 0.680851 (6575 4725);
PAINT MONO (6575 4725);
DISPLAY INVISIBLE (6575 4725);
FORCEPROP 0 LAST CDS_SEC 1
J 0
(6575 4725);
DISPLAY 1.021277 (6575 4725);
DISPLAY INVISIBLE (6575 4725);
FORCEPROP 0 LASTPIN (6400 4550) $PN 1
J 2
(6390 4560);
DISPLAY 0.489362 (6390 4560);
PAINT MONO (6390 4560);
FORCEPROP 0 LASTPIN (6400 4300) $PN 2
J 2
(6390 4310);
DISPLAY 0.489362 (6390 4310);
PAINT MONO (6390 4310);
FORCEPROP 0 LASTPIN (7200 4300) $PN 3
J 0
(7210 4310);
DISPLAY 0.489362 (7210 4310);
PAINT MONO (7210 4310);
FORCEPROP 0 LASTPIN (7200 4550) $PN 4
J 0
(7210 4560);
DISPLAY 0.489362 (7210 4560);
PAINT MONO (7210 4560);
FORCEPROP 2 LAST PART_TYPE SMLF
J 0
(6725 4175);
DISPLAY 1.021277 (6725 4175);
FORCEPROP 1 LAST MATERIAL IND
J 0
(6600 4600);
DISPLAY 0.489362 (6600 4600);
PAINT SKYBLUE (6600 4600);
FORCEPROP 2 LAST VALUE 150NH
J 0
(6700 4600);
DISPLAY 0.489362 (6700 4600);
PAINT SKYBLUE (6700 4600);
FORCEPROP 1 LAST PART_NUMBER CV+15^0TZ04
J 0
(6850 4600);
DISPLAY 0.489362 (6850 4600);
PAINT SKYBLUE (6850 4600);
FORCEPROP 1 LAST NEEDS_NO_SIZE TRUE
J 0
(6800 4425);
DISPLAY 0.468085 (6800 4425);
PAINT GREEN (6800 4425);
DISPLAY INVISIBLE (6800 4425);
FORCEPROP 2 LAST CDS_LIB pure_quanta
J 0
(6800 4425);
DISPLAY INVISIBLE (6800 4425);
FORCEPROP 1 LAST PATH I82
J 0
(7000 4580);
DISPLAY 0.723404 (7000 4580);
PAINT GREEN (7000 4580);
DISPLAY INVISIBLE (7000 4580);
FORCEADD Q_CAP..1
(925 4175);
FORCEPROP 1 LAST LOCATION PC422_5
J 0
(975 4275);
DISPLAY 0.489362 (975 4275);
PAINT SKYBLUE (975 4275);
FORCEPROP 0 LAST $SEC 1
J 0
(975 4300);
DISPLAY 0.680851 (975 4300);
PAINT MONO (975 4300);
DISPLAY INVISIBLE (975 4300);
FORCEPROP 0 LAST CDS_SEC 1
J 0
(1175 4225);
DISPLAY 1.021277 (1175 4225);
DISPLAY INVISIBLE (1175 4225);
FORCEPROP 1 LASTPIN (925 4275) $PN 1
J 0
(935 4255);
DISPLAY 0.489362 (935 4255);
PAINT MONO (935 4255);
FORCEPROP 1 LASTPIN (925 4075) $PN 2
J 0
(935 4055);
DISPLAY 0.489362 (935 4055);
PAINT MONO (935 4055);
FORCEPROP 1 LAST MATERIAL X7R
J 0
(975 4075);
DISPLAY 0.489362 (975 4075);
PAINT SKYBLUE (975 4075);
FORCEPROP 1 LAST TOLERANCE 10%
J 0
(975 4125);
DISPLAY 0.489362 (975 4125);
PAINT SKYBLUE (975 4125);
FORCEPROP 1 LAST VALUE 0.1UF
J 0
(975 4225);
DISPLAY 0.489362 (975 4225);
PAINT SKYBLUE (975 4225);
FORCEPROP 1 LAST PART_NUMBER CH4104K1B00
J 0
(975 4025);
DISPLAY 0.489362 (975 4025);
PAINT SKYBLUE (975 4025);
FORCEPROP 1 LAST VOLTAGE 25V
J 0
(975 4175);
DISPLAY 0.489362 (975 4175);
PAINT SKYBLUE (975 4175);
FORCEPROP 1 LAST PACK_TYPE 0402
J 0
(975 3975);
DISPLAY 0.489362 (975 3975);
PAINT SKYBLUE (975 3975);
FORCEPROP 2 LAST CDS_LIB pure_quanta
J 0
(925 4175);
DISPLAY INVISIBLE (925 4175);
FORCEPROP 1 LAST PATH I83
J 0
(975 4325);
DISPLAY 0.978723 (975 4325);
PAINT WHITE (975 4325);
DISPLAY INVISIBLE (975 4325);
FORCEADD Q_CAP..1
(5600 4775);
FORCEPROP 1 LAST LOCATION PC428
J 0
(5650 4875);
DISPLAY 0.489362 (5650 4875);
PAINT SKYBLUE (5650 4875);
FORCEPROP 0 LAST $SEC 1
J 0
(5650 4925);
DISPLAY 0.680851 (5650 4925);
PAINT MONO (5650 4925);
DISPLAY INVISIBLE (5650 4925);
FORCEPROP 0 LAST CDS_SEC 1
J 2
(5650 4900);
DISPLAY 1.021277 (5650 4900);
DISPLAY INVISIBLE (5650 4900);
FORCEPROP 1 LASTPIN (5600 4875) $PN 1
J 0
(5610 4855);
DISPLAY 0.489362 (5610 4855);
PAINT MONO (5610 4855);
FORCEPROP 1 LASTPIN (5600 4675) $PN 2
J 0
(5610 4655);
DISPLAY 0.489362 (5610 4655);
PAINT MONO (5610 4655);
FORCEPROP 1 LAST MATERIAL X7R
J 0
(5650 4675);
DISPLAY 0.489362 (5650 4675);
PAINT SKYBLUE (5650 4675);
FORCEPROP 1 LAST TOLERANCE 10%
J 0
(5650 4725);
DISPLAY 0.489362 (5650 4725);
PAINT SKYBLUE (5650 4725);
FORCEPROP 1 LAST VALUE 0.22UF
J 0
(5650 4825);
DISPLAY 0.489362 (5650 4825);
PAINT SKYBLUE (5650 4825);
FORCEPROP 1 LAST PART_NUMBER CH4223K1B00
J 0
(5650 4625);
DISPLAY 0.489362 (5650 4625);
PAINT SKYBLUE (5650 4625);
FORCEPROP 1 LAST VOLTAGE 16V
J 0
(5650 4775);
DISPLAY 0.489362 (5650 4775);
PAINT SKYBLUE (5650 4775);
FORCEPROP 1 LAST PACK_TYPE 0402
J 0
(5650 4575);
DISPLAY 0.489362 (5650 4575);
PAINT SKYBLUE (5650 4575);
FORCEPROP 2 LAST CDS_LIB pure_quanta
J 2
(5600 4775);
DISPLAY INVISIBLE (5600 4775);
FORCEPROP 1 LAST PATH I84
J 0
(5650 4925);
DISPLAY 0.978723 (5650 4925);
PAINT WHITE (5650 4925);
DISPLAY INVISIBLE (5650 4925);
FORCEADD Q_RES..1
(4700 4900);
FORCEPROP 1 LAST LOCATION PR272
J 0
(4650 4950);
DISPLAY 0.489362 (4650 4950);
PAINT SKYBLUE (4650 4950);
FORCEPROP 0 LAST $SEC 1
J 0
(4975 5000);
DISPLAY 0.680851 (4975 5000);
PAINT MONO (4975 5000);
DISPLAY INVISIBLE (4975 5000);
FORCEPROP 0 LAST CDS_SEC 1
J 0
(4975 5000);
DISPLAY 1.021277 (4975 5000);
DISPLAY INVISIBLE (4975 5000);
FORCEPROP 1 LASTPIN (4600 4900) $PN 1
J 0
(4612 4912);
DISPLAY 0.787234 (4612 4912);
PAINT MONO (4612 4912);
DISPLAY INVISIBLE (4612 4912);
FORCEPROP 1 LASTPIN (4800 4900) $PN 2
J 0
(4762 4912);
DISPLAY 0.787234 (4762 4912);
PAINT MONO (4762 4912);
DISPLAY INVISIBLE (4762 4912);
FORCEPROP 1 LAST PACK_TYPE 0402LF
J 0
(4750 4800);
DISPLAY 0.489362 (4750 4800);
PAINT SKYBLUE (4750 4800);
FORCEPROP 1 LAST TOLERANCE 1%
J 0
(4525 4800);
DISPLAY 0.489362 (4525 4800);
PAINT SKYBLUE (4525 4800);
FORCEPROP 1 LAST MATERIAL CHIP
J 0
(4775 4850);
DISPLAY 0.489362 (4775 4850);
PAINT SKYBLUE (4775 4850);
FORCEPROP 1 LAST WATTAGE 1/16W
J 2
(4900 4925);
DISPLAY 0.489362 (4900 4925);
PAINT SKYBLUE (4900 4925);
FORCEPROP 1 LAST VALUE 4.7
J 2
(4575 4925);
DISPLAY 0.489362 (4575 4925);
PAINT SKYBLUE (4575 4925);
FORCEPROP 1 LAST PART_NUMBER CS-4702FB19
J 0
(4400 4850);
DISPLAY 0.489362 (4400 4850);
PAINT SKYBLUE (4400 4850);
FORCEPROP 1 LAST PATH I85
J 0
(4650 5050);
DISPLAY 0.978723 (4650 5050);
PAINT WHITE (4650 5050);
DISPLAY INVISIBLE (4650 5050);
FORCEPROP 2 LAST CDS_LIB pure_quanta
J 0
(4700 4900);
DISPLAY INVISIBLE (4700 4900);
FORCEADD Q_CAP..1
(4200 5450);
FORCEPROP 1 LAST LOCATION PC424_5
J 0
(4250 5600);
DISPLAY 0.489362 (4250 5600);
PAINT SKYBLUE (4250 5600);
FORCEPROP 0 LAST $SEC 1
J 0
(4250 5600);
DISPLAY 0.680851 (4250 5600);
PAINT MONO (4250 5600);
DISPLAY INVISIBLE (4250 5600);
FORCEPROP 0 LAST CDS_SEC 1
J 0
(4250 5600);
DISPLAY 1.021277 (4250 5600);
DISPLAY INVISIBLE (4250 5600);
FORCEPROP 1 LASTPIN (4200 5550) $PN 1
J 0
(4210 5530);
DISPLAY 0.489362 (4210 5530);
PAINT MONO (4210 5530);
FORCEPROP 1 LASTPIN (4200 5350) $PN 2
J 0
(4210 5330);
DISPLAY 0.489362 (4210 5330);
PAINT MONO (4210 5330);
FORCEPROP 1 LAST MATERIAL X7R
J 0
(4250 5400);
DISPLAY 0.489362 (4250 5400);
PAINT SKYBLUE (4250 5400);
FORCEPROP 1 LAST TOLERANCE 10%
J 0
(4250 5450);
DISPLAY 0.489362 (4250 5450);
PAINT SKYBLUE (4250 5450);
FORCEPROP 1 LAST VALUE 0.1UF
J 0
(4250 5550);
DISPLAY 0.489362 (4250 5550);
PAINT SKYBLUE (4250 5550);
FORCEPROP 1 LAST PART_NUMBER CH4104K1B00
J 0
(4250 5350);
DISPLAY 0.489362 (4250 5350);
PAINT SKYBLUE (4250 5350);
FORCEPROP 1 LAST VOLTAGE 25V
J 0
(4250 5500);
DISPLAY 0.489362 (4250 5500);
PAINT SKYBLUE (4250 5500);
FORCEPROP 1 LAST PACK_TYPE 0402
J 0
(4250 5300);
DISPLAY 0.489362 (4250 5300);
PAINT SKYBLUE (4250 5300);
FORCEPROP 2 LAST CDS_LIB pure_quanta
J 0
(4200 5450);
DISPLAY INVISIBLE (4200 5450);
FORCEPROP 1 LAST PATH I86
J 0
(4250 5600);
DISPLAY 0.978723 (4250 5600);
PAINT WHITE (4250 5600);
DISPLAY INVISIBLE (4250 5600);
FORCEADD Q_CAP..1
(1875 4975);
FORCEPROP 1 LAST LOCATION PC421
J 0
(1925 5075);
DISPLAY 0.489362 (1925 5075);
PAINT SKYBLUE (1925 5075);
FORCEPROP 0 LAST $SEC 1
J 0
(1925 5125);
DISPLAY 0.680851 (1925 5125);
PAINT MONO (1925 5125);
DISPLAY INVISIBLE (1925 5125);
FORCEPROP 0 LAST CDS_SEC 1
J 0
(1925 5125);
DISPLAY 1.021277 (1925 5125);
DISPLAY INVISIBLE (1925 5125);
FORCEPROP 1 LASTPIN (1875 5075) $PN 1
J 0
(1885 5055);
DISPLAY 0.489362 (1885 5055);
PAINT MONO (1885 5055);
FORCEPROP 1 LASTPIN (1875 4875) $PN 2
J 0
(1885 4855);
DISPLAY 0.489362 (1885 4855);
PAINT MONO (1885 4855);
FORCEPROP 1 LAST MATERIAL X6S
J 0
(1925 4875);
DISPLAY 0.489362 (1925 4875);
PAINT SKYBLUE (1925 4875);
FORCEPROP 1 LAST TOLERANCE 10%
J 0
(1925 4925);
DISPLAY 0.489362 (1925 4925);
PAINT SKYBLUE (1925 4925);
FORCEPROP 1 LAST VALUE 2.2UF
J 0
(1925 5025);
DISPLAY 0.489362 (1925 5025);
PAINT SKYBLUE (1925 5025);
FORCEPROP 1 LAST PART_NUMBER CH5222KEB01
J 0
(1925 4825);
DISPLAY 0.489362 (1925 4825);
PAINT SKYBLUE (1925 4825);
FORCEPROP 1 LAST VOLTAGE 10V
J 0
(1925 4975);
DISPLAY 0.489362 (1925 4975);
PAINT SKYBLUE (1925 4975);
FORCEPROP 1 LAST PACK_TYPE C0402
J 0
(1925 4775);
DISPLAY 0.489362 (1925 4775);
PAINT SKYBLUE (1925 4775);
FORCEPROP 2 LAST CDS_LIB pure_quanta
J 0
(1875 4975);
DISPLAY INVISIBLE (1875 4975);
FORCEPROP 1 LAST PATH I87
J 0
(1925 5125);
DISPLAY 0.978723 (1925 5125);
PAINT WHITE (1925 5125);
DISPLAY INVISIBLE (1925 5125);
FORCEADD UNIVERSAL_GND..1
(1875 4775);
FORCEPROP 3 LASTPIN (1875 4825) SIG_NAME GND\g
J 0
(1885 4835);
DISPLAY 0.659574 (1885 4835);
PAINT MONO (1885 4835);
DISPLAY INVISIBLE (1885 4835);
FORCEPROP 2 LAST CDS_LIB pure_quanta_power
J 0
(1875 4775);
DISPLAY INVISIBLE (1875 4775);
FORCEPROP 1 LAST PATH I88
J 0
(1950 4775);
DISPLAY 0.872340 (1950 4775);
PAINT AQUA (1950 4775);
DISPLAY INVISIBLE (1950 4775);
FORCEPROP 1 LAST HDL_POWER GND
J 1
(1900 4700);
DISPLAY 0.872340 (1900 4700);
PAINT GREEN (1900 4700);
DISPLAY INVISIBLE (1900 4700);
FORCEADD UNIVERSAL_GND..1
(2225 5275);
FORCEPROP 3 LASTPIN (2225 5325) SIG_NAME GND\g
J 0
(2235 5335);
DISPLAY 0.659574 (2235 5335);
PAINT MONO (2235 5335);
DISPLAY INVISIBLE (2235 5335);
FORCEPROP 2 LAST CDS_LIB pure_quanta_power
J 0
(2225 5275);
DISPLAY INVISIBLE (2225 5275);
FORCEPROP 1 LAST PATH I89
J 0
(2300 5275);
DISPLAY 0.872340 (2300 5275);
PAINT AQUA (2300 5275);
DISPLAY INVISIBLE (2300 5275);
FORCEPROP 1 LAST HDL_POWER GND
J 1
(2250 5200);
DISPLAY 0.872340 (2250 5200);
PAINT GREEN (2250 5200);
DISPLAY INVISIBLE (2250 5200);
FORCEADD Q_RES..2
(1875 5525);
FORCEPROP 1 LAST LOCATION PR271
J 0
(1920 5650);
DISPLAY 0.489362 (1920 5650);
PAINT SKYBLUE (1920 5650);
FORCEPROP 0 LAST $SEC 1
J 0
(1925 5700);
DISPLAY 0.680851 (1925 5700);
PAINT MONO (1925 5700);
DISPLAY INVISIBLE (1925 5700);
FORCEPROP 0 LAST CDS_SEC 1
J 0
(1925 5700);
DISPLAY 1.021277 (1925 5700);
DISPLAY INVISIBLE (1925 5700);
FORCEPROP 1 LASTPIN (1875 5625) $PN 1
J 0
(1880 5587);
DISPLAY 0.489362 (1880 5587);
PAINT MONO (1880 5587);
FORCEPROP 1 LASTPIN (1875 5425) $PN 2
J 0
(1880 5435);
DISPLAY 0.489362 (1880 5435);
PAINT MONO (1880 5435);
FORCEPROP 1 LAST WATTAGE 1/16W
J 0
(1925 5500);
DISPLAY 0.489362 (1925 5500);
PAINT SKYBLUE (1925 5500);
FORCEPROP 1 LAST MATERIAL CHIP
J 0
(1925 5450);
DISPLAY 0.489362 (1925 5450);
PAINT SKYBLUE (1925 5450);
FORCEPROP 1 LAST TOLERANCE 1%
J 0
(1925 5550);
DISPLAY 0.489362 (1925 5550);
PAINT SKYBLUE (1925 5550);
FORCEPROP 1 LAST VALUE 2.2
J 0
(1925 5600);
DISPLAY 0.489362 (1925 5600);
PAINT SKYBLUE (1925 5600);
FORCEPROP 1 LAST PART_NUMBER CS-2202FB00
J 0
(1925 5400);
DISPLAY 0.489362 (1925 5400);
PAINT SKYBLUE (1925 5400);
FORCEPROP 1 LAST PACK_TYPE 0402LF
J 0
(1925 5350);
DISPLAY 0.489362 (1925 5350);
PAINT SKYBLUE (1925 5350);
FORCEPROP 2 LAST CDS_LIB pure_quanta
J 0
(1875 5525);
DISPLAY INVISIBLE (1875 5525);
FORCEPROP 1 LAST PATH I90
J 0
(1925 5700);
DISPLAY 0.978723 (1925 5700);
PAINT WHITE (1925 5700);
DISPLAY INVISIBLE (1925 5700);
FORCEADD Q_CAP..1
(2225 5550);
FORCEPROP 1 LAST LOCATION PC423_C1P1_5
J 0
(2275 5650);
DISPLAY 0.489362 (2275 5650);
PAINT SKYBLUE (2275 5650);
FORCEPROP 0 LAST $SEC 1
J 0
(2275 5700);
DISPLAY 0.680851 (2275 5700);
PAINT MONO (2275 5700);
DISPLAY INVISIBLE (2275 5700);
FORCEPROP 0 LAST CDS_SEC 1
J 0
(2275 5700);
DISPLAY 1.021277 (2275 5700);
DISPLAY INVISIBLE (2275 5700);
FORCEPROP 1 LASTPIN (2225 5650) $PN 1
J 0
(2235 5630);
DISPLAY 0.489362 (2235 5630);
PAINT MONO (2235 5630);
FORCEPROP 1 LASTPIN (2225 5450) $PN 2
J 0
(2235 5430);
DISPLAY 0.489362 (2235 5430);
PAINT MONO (2235 5430);
FORCEPROP 1 LAST MATERIAL X6S
J 0
(2275 5450);
DISPLAY 0.489362 (2275 5450);
PAINT SKYBLUE (2275 5450);
FORCEPROP 1 LAST TOLERANCE 10%
J 0
(2275 5500);
DISPLAY 0.489362 (2275 5500);
PAINT SKYBLUE (2275 5500);
FORCEPROP 1 LAST VALUE 2.2UF
J 0
(2275 5600);
DISPLAY 0.489362 (2275 5600);
PAINT SKYBLUE (2275 5600);
FORCEPROP 1 LAST PART_NUMBER CH5222KEB01
J 0
(2275 5400);
DISPLAY 0.489362 (2275 5400);
PAINT SKYBLUE (2275 5400);
FORCEPROP 1 LAST VOLTAGE 10V
J 0
(2275 5550);
DISPLAY 0.489362 (2275 5550);
PAINT SKYBLUE (2275 5550);
FORCEPROP 1 LAST PACK_TYPE C0402
J 0
(2275 5350);
DISPLAY 0.489362 (2275 5350);
PAINT SKYBLUE (2275 5350);
FORCEPROP 2 LAST CDS_LIB pure_quanta
J 0
(2225 5550);
DISPLAY INVISIBLE (2225 5550);
FORCEPROP 1 LAST PATH I91
J 0
(2275 5700);
DISPLAY 0.978723 (2275 5700);
PAINT WHITE (2275 5700);
DISPLAY INVISIBLE (2275 5700);
FORCEADD UNIVERSAL_GND..1
(925 3975);
FORCEPROP 3 LASTPIN (925 4025) SIG_NAME GND\g
J 0
(935 4035);
DISPLAY 0.659574 (935 4035);
PAINT MONO (935 4035);
DISPLAY INVISIBLE (935 4035);
FORCEPROP 2 LAST CDS_LIB pure_quanta_power
J 0
(925 3975);
DISPLAY INVISIBLE (925 3975);
FORCEPROP 1 LAST PATH I93
J 0
(1000 3975);
DISPLAY 0.872340 (1000 3975);
PAINT AQUA (1000 3975);
DISPLAY INVISIBLE (1000 3975);
FORCEPROP 1 LAST HDL_POWER GND
J 1
(950 3900);
DISPLAY 0.872340 (950 3900);
PAINT GREEN (950 3900);
DISPLAY INVISIBLE (950 3900);
FORCEADD ISL99390FRZTR5935..1
(3400 1925);
FORCEPROP 1 LAST LOCATION PU33
J 0
(3100 2800);
DISPLAY 0.489362 (3100 2800);
PAINT SKYBLUE (3100 2800);
FORCEPROP 2 LAST $SEC 1
J 0
(3100 2975);
DISPLAY 0.680851 (3100 2975);
PAINT MONO (3100 2975);
DISPLAY INVISIBLE (3100 2975);
FORCEPROP 2 LAST CDS_SEC 1
J 0
(3100 2975);
DISPLAY 1.021277 (3100 2975);
DISPLAY INVISIBLE (3100 2975);
FORCEPROP 2 LASTPIN (3800 1475) $PN 2
J 0
(3810 1485);
DISPLAY 0.489362 (3810 1485);
PAINT MONO (3810 1485);
FORCEPROP 2 LASTPIN (3800 2275) $PN 33
J 0
(3810 2285);
DISPLAY 0.489362 (3810 2285);
PAINT MONO (3810 2285);
FORCEPROP 2 LASTPIN (2950 1675) $PN 31
J 2
(2940 1685);
DISPLAY 0.489362 (2940 1685);
PAINT MONO (2940 1685);
FORCEPROP 2 LASTPIN (2950 2075) $PN 35
J 2
(2940 2085);
DISPLAY 0.489362 (2940 2085);
PAINT MONO (2940 2085);
FORCEPROP 2 LASTPIN (3800 1625) $PN 6
J 0
(3810 1635);
DISPLAY 0.489362 (3810 1635);
PAINT MONO (3810 1635);
FORCEPROP 2 LASTPIN (3800 1575) $PN 41
J 0
(3810 1585);
DISPLAY 0.489362 (3810 1585);
PAINT MONO (3810 1585);
FORCEPROP 2 LASTPIN (2950 1925) $PN 38
J 2
(2940 1935);
DISPLAY 0.489362 (2940 1935);
PAINT MONO (2940 1935);
FORCEPROP 2 LASTPIN (2950 1625) $PN 37
J 2
(2940 1635);
DISPLAY 0.489362 (2940 1635);
PAINT MONO (2940 1635);
FORCEPROP 2 LASTPIN (3800 1425) $PN 5
J 0
(3810 1435);
DISPLAY 0.489362 (3810 1435);
PAINT MONO (3810 1435);
FORCEPROP 2 LASTPIN (3800 1375) $PN 7_9-20_24
J 0
(3810 1385);
DISPLAY 0.489362 (3810 1385);
PAINT MONO (3810 1385);
FORCEPROP 2 LASTPIN (3800 1325) $PN 40
J 0
(3810 1335);
DISPLAY 0.489362 (3810 1335);
PAINT MONO (3810 1335);
FORCEPROP 2 LASTPIN (3800 2025) $PN 32
J 0
(3810 2035);
DISPLAY 0.489362 (3810 2035);
PAINT MONO (3810 2035);
FORCEPROP 2 LASTPIN (2950 2575) $PN 4
J 2
(2940 2585);
DISPLAY 0.489362 (2940 2585);
PAINT MONO (2940 2585);
FORCEPROP 2 LASTPIN (2950 1325) $PN 34
J 2
(2940 1335);
DISPLAY 0.489362 (2940 1335);
PAINT MONO (2940 1335);
FORCEPROP 2 LASTPIN (2950 1825) $PN 39
J 2
(2940 1835);
DISPLAY 0.489362 (2940 1835);
PAINT MONO (2940 1835);
FORCEPROP 2 LASTPIN (3800 1925) $PN 10_19
J 0
(3810 1935);
DISPLAY 0.489362 (3810 1935);
PAINT MONO (3810 1935);
FORCEPROP 2 LASTPIN (2950 1425) $PN 36
J 2
(2940 1435);
DISPLAY 0.489362 (2940 1435);
PAINT MONO (2940 1435);
FORCEPROP 2 LASTPIN (2950 2275) $PN 3
J 2
(2940 2285);
DISPLAY 0.489362 (2940 2285);
PAINT MONO (2940 2285);
FORCEPROP 2 LASTPIN (3800 2575) $PN 25_29
J 0
(3810 2585);
DISPLAY 0.489362 (3810 2585);
PAINT MONO (3810 2585);
FORCEPROP 2 LASTPIN (3800 2525) $PN 30
J 0
(3810 2535);
DISPLAY 0.489362 (3810 2535);
PAINT MONO (3810 2535);
FORCEPROP 2 LASTPIN (3800 1675) $PN 1
J 0
(3810 1685);
DISPLAY 0.489362 (3810 1685);
PAINT MONO (3810 1685);
FORCEPROP 2 LAST PART_TYPE SMLF
J 0
(3100 2950);
DISPLAY 0.638298 (3100 2950);
FORCEPROP 1 LAST MATERIAL IC
J 0
(3100 2650);
DISPLAY 0.489362 (3100 2650);
PAINT SKYBLUE (3100 2650);
FORCEPROP 2 LAST VALUE ISL99390FRZ-TR5935
J 0
(3100 2900);
DISPLAY 0.489362 (3100 2900);
PAINT SKYBLUE (3100 2900);
FORCEPROP 1 LAST PART_NUMBER AL099390004
J 0
(3100 2725);
DISPLAY 0.489362 (3100 2725);
PAINT SKYBLUE (3100 2725);
FORCEPROP 1 LAST NEEDS_NO_SIZE TRUE
J 0
(3400 1925);
DISPLAY 0.723404 (3400 1925);
PAINT GREEN (3400 1925);
DISPLAY INVISIBLE (3400 1925);
FORCEPROP 1 LAST CDS_LMAN_SYM_OUTLINE -300,700,250,-650
J 0
(3400 1925);
DISPLAY 0.468085 (3400 1925);
PAINT GREEN (3400 1925);
DISPLAY INVISIBLE (3400 1925);
FORCEPROP 2 LAST CDS_LIB pure_quanta
J 0
(3400 1925);
DISPLAY INVISIBLE (3400 1925);
FORCEPROP 1 LAST PATH I94
J 0
(3400 1925);
DISPLAY 0.723404 (3400 1925);
PAINT GREEN (3400 1925);
DISPLAY INVISIBLE (3400 1925);
FORCEADD VCC_CORE..1
(8775 2075);
FORCEPROP 3 LASTPIN (8775 2025) SIG_NAME PVDDCR_CPU1_P1\g
J 0
(8785 2035);
DISPLAY 0.659574 (8785 2035);
PAINT MONO (8785 2035);
DISPLAY INVISIBLE (8785 2035);
FORCEPROP 1 LAST HDL_POWER PVDDCR_CPU1_P1
J 1
(8775 2125);
DISPLAY 0.489362 (8775 2125);
PAINT GREEN (8775 2125);
FORCEPROP 2 LAST CDS_LIB pure_quanta_power
J 0
(8775 2075);
DISPLAY INVISIBLE (8775 2075);
FORCEPROP 1 LAST PATH I95
J 0
(8825 2100);
DISPLAY 0.872340 (8825 2100);
PAINT AQUA (8825 2100);
DISPLAY INVISIBLE (8825 2100);
FORCEADD Q_CAP..1
(8775 1725);
FORCEPROP 1 LAST LOCATION PC149_6
J 0
(8825 1850);
DISPLAY 0.489362 (8825 1850);
PAINT SKYBLUE (8825 1850);
FORCEPROP 0 LAST $SEC 1
J 0
(8825 1900);
DISPLAY 0.680851 (8825 1900);
PAINT MONO (8825 1900);
DISPLAY INVISIBLE (8825 1900);
FORCEPROP 0 LAST CDS_SEC 1
J 0
(8825 1900);
DISPLAY 1.021277 (8825 1900);
DISPLAY INVISIBLE (8825 1900);
FORCEPROP 1 LASTPIN (8775 1825) $PN 1
J 0
(8785 1805);
DISPLAY 0.489362 (8785 1805);
PAINT MONO (8785 1805);
FORCEPROP 1 LASTPIN (8775 1625) $PN 2
J 0
(8785 1605);
DISPLAY 0.489362 (8785 1605);
PAINT MONO (8785 1605);
FORCEPROP 1 LAST MATERIAL X6S
J 0
(8825 1650);
DISPLAY 0.489362 (8825 1650);
PAINT SKYBLUE (8825 1650);
FORCEPROP 1 LAST TOLERANCE 20%
J 0
(8825 1700);
DISPLAY 0.489362 (8825 1700);
PAINT SKYBLUE (8825 1700);
FORCEPROP 1 LAST VALUE 22UF
J 0
(8825 1800);
DISPLAY 0.489362 (8825 1800);
PAINT SKYBLUE (8825 1800);
FORCEPROP 1 LAST PART_NUMBER TMP_QCH622KMEA01
J 0
(8825 1550);
DISPLAY 0.489362 (8825 1550);
PAINT SKYBLUE (8825 1550);
FORCEPROP 1 LAST VOLTAGE 4V
J 0
(8825 1750);
DISPLAY 0.489362 (8825 1750);
PAINT SKYBLUE (8825 1750);
FORCEPROP 1 LAST PACK_TYPE 0805
J 0
(8825 1600);
DISPLAY 0.489362 (8825 1600);
PAINT SKYBLUE (8825 1600);
FORCEPROP 2 LAST CDS_LIB pure_quanta
J 0
(8775 1725);
DISPLAY INVISIBLE (8775 1725);
FORCEPROP 1 LAST PATH I96
J 0
(8825 1875);
DISPLAY 0.978723 (8825 1875);
PAINT WHITE (8825 1875);
DISPLAY INVISIBLE (8825 1875);
FORCEADD Q_CAP..1
(8350 1725);
FORCEPROP 1 LAST LOCATION PC148_6
J 0
(8400 1850);
DISPLAY 0.489362 (8400 1850);
PAINT SKYBLUE (8400 1850);
FORCEPROP 0 LAST $SEC 1
J 0
(8400 1900);
DISPLAY 0.680851 (8400 1900);
PAINT MONO (8400 1900);
DISPLAY INVISIBLE (8400 1900);
FORCEPROP 0 LAST CDS_SEC 1
J 0
(8400 1900);
DISPLAY 1.021277 (8400 1900);
DISPLAY INVISIBLE (8400 1900);
FORCEPROP 1 LASTPIN (8350 1825) $PN 1
J 0
(8360 1805);
DISPLAY 0.489362 (8360 1805);
PAINT MONO (8360 1805);
FORCEPROP 1 LASTPIN (8350 1625) $PN 2
J 0
(8360 1605);
DISPLAY 0.489362 (8360 1605);
PAINT MONO (8360 1605);
FORCEPROP 1 LAST MATERIAL X6S
J 0
(8400 1650);
DISPLAY 0.489362 (8400 1650);
PAINT SKYBLUE (8400 1650);
FORCEPROP 1 LAST TOLERANCE 20%
J 0
(8400 1700);
DISPLAY 0.489362 (8400 1700);
PAINT SKYBLUE (8400 1700);
FORCEPROP 1 LAST VALUE 22UF
J 0
(8400 1800);
DISPLAY 0.489362 (8400 1800);
PAINT SKYBLUE (8400 1800);
FORCEPROP 1 LAST PART_NUMBER TMP_QCH622KMEA01
J 0
(8400 1550);
DISPLAY 0.489362 (8400 1550);
PAINT SKYBLUE (8400 1550);
FORCEPROP 1 LAST VOLTAGE 4V
J 0
(8400 1750);
DISPLAY 0.489362 (8400 1750);
PAINT SKYBLUE (8400 1750);
FORCEPROP 1 LAST PACK_TYPE 0805
J 0
(8400 1600);
DISPLAY 0.489362 (8400 1600);
PAINT SKYBLUE (8400 1600);
FORCEPROP 2 LAST CDS_LIB pure_quanta
J 0
(8350 1725);
DISPLAY INVISIBLE (8350 1725);
FORCEPROP 1 LAST PATH I97
J 0
(8400 1875);
DISPLAY 0.978723 (8400 1875);
PAINT WHITE (8400 1875);
DISPLAY INVISIBLE (8400 1875);
FORCEADD UNIVERSAL_GND..1
(8775 1375);
FORCEPROP 3 LASTPIN (8775 1425) SIG_NAME GND\g
J 0
(8785 1435);
DISPLAY 0.659574 (8785 1435);
PAINT MONO (8785 1435);
DISPLAY INVISIBLE (8785 1435);
FORCEPROP 2 LAST CDS_LIB pure_quanta_power
J 0
(8775 1375);
PAINT MONO (8775 1375);
DISPLAY INVISIBLE (8775 1375);
FORCEPROP 1 LAST PATH I98
J 0
(8850 1375);
DISPLAY 0.872340 (8850 1375);
PAINT AQUA (8850 1375);
DISPLAY INVISIBLE (8850 1375);
FORCEPROP 1 LAST HDL_POWER GND
J 1
(8800 1300);
DISPLAY 0.872340 (8800 1300);
PAINT GREEN (8800 1300);
DISPLAY INVISIBLE (8800 1300);
FORCEADD OFFPAGE..3
(7875 1675);
FORCEPROP 2 LAST $XR0 196 
J 0
(8179 1675);
DISPLAY 0.638298 (8179 1675);
PAINT MONO (8179 1675);
FORCEPROP 2 LAST PATH I99
J 0
(8200 1725);
DISPLAY 1.021277 (8200 1725);
DISPLAY INVISIBLE (8200 1725);
FORCEPROP 1 LAST COMMENT_BODY TRUE
J 0
(7825 1575);
DISPLAY 0.872340 (7825 1575);
PAINT GREEN (7825 1575);
DISPLAY INVISIBLE (7825 1575);
FORCEPROP 1 LAST OFFPAGE TRUE
J 0
(8200 1550);
DISPLAY 0.872340 (8200 1550);
PAINT GREEN (8200 1550);
DISPLAY INVISIBLE (8200 1550);
FORCEPROP 2 LAST CDS_LIB standard
J 0
(7875 1675);
DISPLAY INVISIBLE (7875 1675);
FORCEADD DNS..1
(1425 4025);
PAINT RED (1425 4025);
FORCEPROP 2 LAST CDS_LIB mstr_misc
J 0
(1425 4025);
PAINT MONO (1425 4025);
DISPLAY INVISIBLE (1425 4025);
FORCEPROP 1 LAST COMMENT_BODY TRUE
R 1
J 0
(1500 3800);
DISPLAY 0.872340 (1500 3800);
PAINT GREEN (1500 3800);
DISPLAY INVISIBLE (1500 3800);
FORCEADD DNS..1
(4900 1200);
PAINT RED (4900 1200);
FORCEPROP 2 LAST CDS_LIB mstr_misc
J 0
(4900 1200);
DISPLAY INVISIBLE (4900 1200);
FORCEPROP 1 LAST COMMENT_BODY TRUE
R 1
J 0
(4975 975);
DISPLAY 0.872340 (4975 975);
PAINT GREEN (4975 975);
DISPLAY INVISIBLE (4975 975);
FORCEADD QUANTA_TITLE_BLOCK_C..1
(9400 100);
FORCEPROP 0 LAST CDS_CON_LAST_MODIFIED Fri Mar 11 14:53:36 2022
J 0
(7515 115);
DISPLAY INVISIBLE (7515 115);
FORCEPROP 1 LAST CUSTOM_TXT_CDS <CON_LAST_MODIFIED>
J 0
(7515 115);
DISPLAY 0.978723 (7515 115);
FORCEPROP 2 LAST CUSTOM_TXT_CDS <XR_PAGE_TITLE>
J 0
(1510 5350);
DISPLAY 0.638298 (1510 5350);
PAINT PINK (1510 5350);
DISPLAY INVISIBLE (1510 5350);
FORCEPROP 1 LAST CUSTOM_TXT_CDS <NAME_2>
J 0
(6225 150);
FORCEPROP 1 LAST CUSTOM_TXT_CDS <NAME_1>
J 0
(6225 275);
FORCEPROP 1 LAST CUSTOM_TXT_CDS <Q_NUMBER>
J 0
(7997 203);
DISPLAY 1.212766 (7997 203);
FORCEPROP 1 LAST CUSTOM_TXT_CDS <Q_PROJ>
J 0
(7018 202);
DISPLAY 1.212766 (7018 202);
FORCEPROP 1 LAST CUSTOM_TXT_CDS <Q_REV>
J 0
(9216 203);
DISPLAY 1.212766 (9216 203);
FORCEPROP 1 LAST CUSTOM_TXT_CDS <CON_PAGE_NUM> OF <CON_TOTAL_PAGES>
J 0
(8954 118);
DISPLAY 0.978723 (8954 118);
FORCEPROP 1 LAST Q_DEPT BU9
J 1
(5637 149);
DISPLAY 1.957447 (5637 149);
PAINT GREEN (5637 149);
FORCEPROP 1 LAST Q_TITLE PVDDCR_CPU1_P1 VR PHASE 5&6
J 0
(100 175);
DISPLAY 2.446809 (100 175);
PAINT GREEN (100 175);
FORCEPROP 2 LAST CDS_LIB pure_quanta
J 0
(9400 100);
DISPLAY INVISIBLE (9400 100);
FORCEPROP 1 LAST CDS_LMAN_SYM_OUTLINE -9475,6775,100,-125
J 0
(9400 100);
DISPLAY 0.468085 (9400 100);
PAINT GREEN (9400 100);
DISPLAY INVISIBLE (9400 100);
FORCEPROP 2 LAST PAGE_BORDER TRUE
J 0
(1510 5350);
DISPLAY 0.638298 (1510 5350);
PAINT PINK (1510 5350);
DISPLAY INVISIBLE (1510 5350);
FORCEPROP 1 LAST COMMENT_BODY TRUE
J 0
(9412 87);
DISPLAY 0.978723 (9412 87);
PAINT GREEN (9412 87);
DISPLAY INVISIBLE (9412 87);
FORCEPROP 2 LAST CDS_XR_PAGE_TITLE CR-196 : @T6G_MB_LIB.T6G(SCH_1):PAGE196
J 0
(1510 5350);
DISPLAY 0.638298 (1510 5350);
PAINT PINK (1510 5350);
DISPLAY INVISIBLE (1510 5350);
FORCEADD DNS..1
(4825 4350);
PAINT RED (4825 4350);
FORCEPROP 2 LAST CDS_LIB mstr_misc
J 0
(4825 4350);
DISPLAY INVISIBLE (4825 4350);
FORCEPROP 1 LAST COMMENT_BODY TRUE
R 1
J 0
(4900 4125);
DISPLAY 0.872340 (4900 4125);
PAINT GREEN (4900 4125);
DISPLAY INVISIBLE (4900 4125);
FORCEADD DNS..1
(4900 1725);
PAINT RED (4900 1725);
FORCEPROP 2 LAST CDS_LIB mstr_misc
J 0
(4900 1725);
DISPLAY INVISIBLE (4900 1725);
FORCEPROP 1 LAST COMMENT_BODY TRUE
R 1
J 0
(4975 1500);
DISPLAY 0.872340 (4975 1500);
PAINT GREEN (4975 1500);
DISPLAY INVISIBLE (4975 1500);
FORCEADD DNS..1
(1475 1400);
PAINT RED (1475 1400);
FORCEPROP 2 LAST CDS_LIB mstr_misc
J 0
(1475 1400);
PAINT MONO (1475 1400);
DISPLAY INVISIBLE (1475 1400);
FORCEPROP 1 LAST COMMENT_BODY TRUE
R 1
J 0
(1550 1175);
DISPLAY 0.872340 (1550 1175);
PAINT GREEN (1550 1175);
DISPLAY INVISIBLE (1550 1175);
FORCEADD DNS..1
(4825 3875);
PAINT RED (4825 3875);
FORCEPROP 2 LAST CDS_LIB mstr_misc
J 0
(4825 3875);
DISPLAY INVISIBLE (4825 3875);
FORCEPROP 1 LAST COMMENT_BODY TRUE
R 1
J 0
(4900 3650);
DISPLAY 0.872340 (4900 3650);
PAINT GREEN (4900 3650);
DISPLAY INVISIBLE (4900 3650);
WIRE 16 -1 (2275 2825)(2275 2700);
WIRE 16 -1 (1925 2250)(1925 2200);
WIRE 16 -1 (1475 1325)(1475 1250);
WIRE 16 -1 (975 1400)(975 1450);
WIRE 16 -1 (4925 1100)(4925 1025);
WIRE 16 -1 (4850 3775)(4850 3700);
WIRE 16 -1 (5675 1675)(5575 1675);
WIRE 16 -1 (5575 1675)(5575 1625);
WIRE 16 -1 (1425 3950)(1425 3875);
WIRE 16 -1 (1875 4875)(1875 4825);
WIRE 16 -1 (2225 5450)(2225 5325);
WIRE 16 -1 (925 4025)(925 4075);
WIRE 16 -1 (4850 2275)(5650 2275);
FORCEPROP 2 LAST SIG_NAME SW_PVDDCR_CPU1_P1_BOOT6_R
J 0
(5015 2285);
DISPLAY 0.489362 (5015 2285);
FORCEPROP 2 LASTPROP $XRERR UNIQUE?
J 0
(4775 2285);
DISPLAY 0.638298 (4775 2285);
PAINT MONO (4775 2285);
DISPLAY INVISIBLE (4775 2285);
WIRE 16 -1 (5650 2275)(5650 2250);
WIRE 16 -1 (5850 2525)(5850 2575);
WIRE 16 -1 (5850 2725)(5850 2575);
WIRE 16 -1 (5475 2575)(5850 2575);
WIRE 16 -1 (5475 2725)(5475 2575);
WIRE 16 -1 (5075 2575)(5475 2575);
WIRE 16 -1 (5075 2725)(5075 2575);
WIRE 16 -1 (5075 2575)(4675 2575);
WIRE 16 -1 (4675 2725)(4675 2575);
WIRE 16 -1 (4250 2575)(4675 2575);
WIRE 16 -1 (4250 2725)(4250 2575);
WIRE 16 -1 (3800 1925)(4925 1925);
FORCEPROP 2 LAST SIG_NAME SW_PVDDCR_CPU1_P1_SW6
J 0
(3990 1935);
DISPLAY 0.489362 (3990 1935);
FORCEPROP 2 LASTPROP $XRERR UNIQUE?
J 0
(3750 1935);
DISPLAY 0.638298 (3750 1935);
PAINT MONO (3750 1935);
DISPLAY INVISIBLE (3750 1935);
WIRE 16 -1 (4925 1925)(6450 1925);
WIRE 16 -1 (4925 1825)(4925 1925);
WIRE 16 -1 (3800 2025)(5650 2025);
FORCEPROP 2 LAST SIG_NAME SW_PVDDCR_CPU1_P1_BOOTR6
J 0
(3990 2035);
DISPLAY 0.489362 (3990 2035);
FORCEPROP 2 LASTPROP $XRERR UNIQUE?
J 0
(3750 2035);
DISPLAY 0.638298 (3750 2035);
PAINT MONO (3750 2035);
DISPLAY INVISIBLE (3750 2035);
WIRE 16 -1 (5650 2025)(5650 2050);
WIRE 16 -1 (3750 4650)(5600 4650);
FORCEPROP 2 LAST SIG_NAME SW_PVDDCR_CPU1_P1_BOOTR5
J 0
(3940 4660);
DISPLAY 0.489362 (3940 4660);
FORCEPROP 2 LASTPROP $XRERR UNIQUE?
J 0
(3700 4660);
DISPLAY 0.638298 (3700 4660);
PAINT MONO (3700 4660);
DISPLAY INVISIBLE (3700 4660);
WIRE 16 -1 (5600 4650)(5600 4675);
WIRE 16 -1 (4850 4450)(4850 4550);
WIRE 16 -1 (4850 4550)(6400 4550);
WIRE 16 -1 (3750 4550)(4850 4550);
FORCEPROP 2 LAST SIG_NAME SW_PVDDCR_CPU1_P1_SW5
J 0
(3940 4560);
DISPLAY 0.489362 (3940 4560);
FORCEPROP 2 LASTPROP $XRERR UNIQUE?
J 0
(3700 4560);
DISPLAY 0.638298 (3700 4560);
PAINT MONO (3700 4560);
DISPLAY INVISIBLE (3700 4560);
WIRE 16 -1 (8725 4125)(8300 4125);
WIRE 16 -1 (8725 4050)(8725 4125);
WIRE 16 -1 (8725 4250)(8725 4125);
WIRE 16 -1 (8300 4125)(8300 4250);
WIRE 16 -1 (8775 1500)(8350 1500);
WIRE 16 -1 (8775 1625)(8775 1500);
WIRE 16 -1 (8775 1425)(8775 1500);
WIRE 16 -1 (8350 1500)(8350 1625);
WIRE 16 -1 (5900 4300)(6400 4300);
FORCEPROP 2 LAST SIG_NAME IND_CPU1_P1_CPL6
J 0
(5940 4310);
DISPLAY 0.489362 (5940 4310);
WIRE 16 -1 (4800 4900)(5600 4900);
FORCEPROP 2 LAST SIG_NAME SW_PVDDCR_CPU1_P1_BOOT5_R
J 0
(4965 4910);
DISPLAY 0.489362 (4965 4910);
FORCEPROP 2 LASTPROP $XRERR UNIQUE?
J 0
(4725 4910);
DISPLAY 0.638298 (4725 4910);
PAINT MONO (4725 4910);
DISPLAY INVISIBLE (4725 4910);
WIRE 16 -1 (5600 4900)(5600 4875);
WIRE 16 -1 (4200 5350)(4200 5200);
WIRE 16 -1 (4200 5200)(4625 5200);
WIRE 16 -1 (5025 5200)(4625 5200);
WIRE 16 -1 (4625 5350)(4625 5200);
WIRE 16 -1 (5025 5200)(5425 5200);
WIRE 16 -1 (5025 5350)(5025 5200);
WIRE 16 -1 (5425 5200)(5800 5200);
WIRE 16 -1 (5425 5350)(5425 5200);
WIRE 16 -1 (5800 5150)(5800 5200);
WIRE 16 -1 (5800 5350)(5800 5200);
WIRE 16 -1 (4850 4250)(4850 3975);
FORCEPROP 2 LAST SIG_NAME SW_PVDDCR_CPU1_P1_SW5_RC
J 0
(4890 4085);
DISPLAY 0.489362 (4890 4085);
FORCEPROP 2 LASTPROP $XRERR UNIQUE?
J 0
(4650 4085);
DISPLAY 0.638298 (4650 4085);
PAINT MONO (4650 4085);
DISPLAY INVISIBLE (4650 4085);
WIRE 16 -1 (7250 1675)(7825 1675);
FORCEPROP 2 LAST SIG_NAME IND_CPU1_P1_CPL6
J 0
(7390 1685);
DISPLAY 0.489362 (7390 1685);
WIRE 16 -1 (8150 1925)(8150 775);
WIRE 16 -1 (8350 1925)(8150 1925);
WIRE 16 -1 (8150 1925)(7250 1925);
WIRE 16 -1 (8150 775)(6050 775);
WIRE 16 -1 (8350 1925)(8775 1925);
WIRE 16 -1 (8350 1925)(8350 1825);
WIRE 16 -1 (8775 2025)(8775 1925);
WIRE 16 -1 (8775 1825)(8775 1925);
WIRE 16 -1 (4925 1625)(4925 1300);
FORCEPROP 2 LAST SIG_NAME SW_PVDDCR_CPU1_P1_SW6_RC
J 0
(4990 1435);
DISPLAY 0.489362 (4990 1435);
FORCEPROP 2 LASTPROP $XRERR UNIQUE?
J 0
(4750 1435);
DISPLAY 0.638298 (4750 1435);
PAINT MONO (4750 1435);
DISPLAY INVISIBLE (4750 1435);
WIRE 16 -1 (3800 1625)(4400 1625);
FORCEPROP 2 LAST SIG_NAME NC_PVDDCR_CPU1_P1_GL1_6
J 0
(3915 1635);
DISPLAY 0.489362 (3915 1635);
FORCEPROP 2 LASTPROP $XRERR UNIQUE?
J 0
(4430 1625);
DISPLAY 0.638298 (4430 1625);
PAINT MONO (4430 1625);
DISPLAY INVISIBLE (4430 1625);
WIRE 16 -1 (3800 1575)(4400 1575);
FORCEPROP 2 LAST SIG_NAME NC_PVDDCR_CPU1_P1_GL2_6
J 0
(3915 1585);
DISPLAY 0.489362 (3915 1585);
FORCEPROP 2 LASTPROP $XRERR UNIQUE?
J 0
(4430 1575);
DISPLAY 0.638298 (4430 1575);
PAINT MONO (4430 1575);
DISPLAY INVISIBLE (4430 1575);
WIRE 16 -1 (3800 2275)(4650 2275);
FORCEPROP 2 LAST SIG_NAME SW_PVDDCR_CPU1_P1_BOOT6
J 0
(4015 2285);
DISPLAY 0.489362 (4015 2285);
FORCEPROP 2 LASTPROP $XRERR UNIQUE?
J 0
(3775 2285);
DISPLAY 0.638298 (3775 2285);
PAINT MONO (3775 2285);
DISPLAY INVISIBLE (3775 2285);
WIRE 16 -1 (3750 4900)(4600 4900);
FORCEPROP 2 LAST SIG_NAME SW_PVDDCR_CPU1_P1_BOOT5
J 0
(3965 4910);
DISPLAY 0.489362 (3965 4910);
FORCEPROP 2 LASTPROP $XRERR UNIQUE?
J 0
(3725 4910);
DISPLAY 0.638298 (3725 4910);
PAINT MONO (3725 4910);
DISPLAY INVISIBLE (3725 4910);
WIRE 16 -1 (3750 4250)(4350 4250);
FORCEPROP 2 LAST SIG_NAME NC_PVDDCR_CPU1_P1_GL1_5
J 0
(3865 4260);
DISPLAY 0.489362 (3865 4260);
FORCEPROP 2 LASTPROP $XRERR UNIQUE?
J 0
(4380 4250);
DISPLAY 0.638298 (4380 4250);
PAINT MONO (4380 4250);
DISPLAY INVISIBLE (4380 4250);
WIRE 16 -1 (3750 4200)(4350 4200);
FORCEPROP 2 LAST SIG_NAME NC_PVDDCR_CPU1_P1_GL2_5
J 0
(3865 4210);
DISPLAY 0.489362 (3865 4210);
FORCEPROP 2 LASTPROP $XRERR UNIQUE?
J 0
(4380 4200);
DISPLAY 0.638298 (4380 4200);
PAINT MONO (4380 4200);
DISPLAY INVISIBLE (4380 4200);
WIRE 16 -1 (3750 5150)(3925 5150);
WIRE 16 -1 (3925 5150)(3925 5200);
WIRE 16 -1 (3750 5200)(3925 5200);
WIRE 16 -1 (3925 5700)(3925 5200);
WIRE 16 -1 (4200 5700)(3925 5700);
WIRE 16 -1 (4625 5700)(4200 5700);
WIRE 16 -1 (4200 5550)(4200 5700);
WIRE 16 -1 (4625 5700)(5025 5700);
WIRE 16 -1 (4625 5550)(4625 5700);
WIRE 16 -1 (5025 5700)(5425 5700);
WIRE 16 -1 (5025 5700)(5025 5550);
WIRE 16 -1 (5425 5700)(5800 5700);
WIRE 16 -1 (5425 5550)(5425 5700);
WIRE 16 -1 (5800 5750)(5800 5700);
WIRE 16 -1 (5800 5550)(5800 5700);
WIRE 16 -1 (2900 4300)(2525 4300);
FORCEPROP 2 LAST SIG_NAME NC_PVDDCR_CPU1_P1_DNC5
J 0
(2330 4310);
DISPLAY 0.489362 (2330 4310);
FORCEPROP 2 LASTPROP $XRERR UNIQUE?
J 0
(2285 4300);
DISPLAY 0.638298 (2285 4300);
PAINT MONO (2285 4300);
DISPLAY INVISIBLE (2285 4300);
WIRE 16 -1 (2900 4550)(1950 4550);
FORCEPROP 2 LAST SIG_NAME PVDDCR_CPU1_P1_IMON5
J 0
(2065 4560);
DISPLAY 0.489362 (2065 4560);
WIRE 16 -1 (2800 4375)(925 4375);
WIRE 16 -1 (2800 4450)(2800 4375);
FORCEPROP 0 LAST CDS_PHYS_NET_NAME PVCCIN_CPU0_VREF
J 0
(2800 4400);
PAINT MONO (2800 4400);
DISPLAY INVISIBLE (2800 4400);
WIRE 16 -1 (925 4375)(925 4275);
WIRE 16 -1 (1950 4450)(2800 4450);
FORCEPROP 2 LAST SIG_NAME PVDDCR_CPU1_P1_VCCS
J 0
(2065 4460);
DISPLAY 0.489362 (2065 4460);
WIRE 16 -1 (2800 4450)(2900 4450);
WIRE 16 -1 (1875 5075)(1875 5175);
WIRE 16 -1 (1875 5175)(2200 5175);
WIRE 16 -1 (1875 5425)(1875 5175);
WIRE 16 -1 (2200 5175)(2200 4900);
WIRE 16 -1 (2800 4900)(2200 4900);
FORCEPROP 2 LAST SIG_NAME PVDDCR_CPU1_P1_VCC5
J 0
(2265 4910);
DISPLAY 0.489362 (2265 4910);
FORCEPROP 2 LASTPROP $XRERR UNIQUE?
J 0
(2025 4910);
DISPLAY 0.638298 (2025 4910);
PAINT MONO (2025 4910);
DISPLAY INVISIBLE (2025 4910);
WIRE 16 -1 (2800 4900)(2900 4900);
WIRE 16 -1 (2800 4700)(2800 4900);
WIRE 16 -1 (2900 4700)(2800 4700);
WIRE 16 -1 (1425 4250)(2900 4250);
FORCEPROP 2 LAST SIG_NAME PVDDCR_CPU1_P1_LSET5
J 0
(1940 4260);
DISPLAY 0.489362 (1940 4260);
FORCEPROP 2 LASTPROP $XRERR UNIQUE?
J 0
(1700 4260);
DISPLAY 0.638298 (1700 4260);
PAINT MONO (1700 4260);
DISPLAY INVISIBLE (1700 4260);
WIRE 16 -1 (1425 4250)(1425 4150);
WIRE 16 -1 (1875 5625)(1875 5750);
WIRE 16 -1 (2225 5750)(1875 5750);
WIRE 16 -1 (1875 5875)(1875 5750);
WIRE 16 -1 (2225 5650)(2225 5750);
WIRE 16 -1 (2550 5750)(2225 5750);
WIRE 16 -1 (2550 5200)(2550 5750);
WIRE 16 -1 (2900 5200)(2550 5200);
WIRE 16 -1 (3750 4100)(4000 4100);
WIRE 16 -1 (4000 4100)(4000 4050);
WIRE 16 -1 (3750 4050)(4000 4050);
WIRE 16 -1 (4000 4050)(4000 4000);
WIRE 16 -1 (4000 4000)(4000 3950);
WIRE 16 -1 (3750 4000)(4000 4000);
WIRE 16 -1 (4000 3950)(4000 3875);
WIRE 16 -1 (3750 3950)(4000 3950);
WIRE 16 -1 (2950 1675)(2575 1675);
FORCEPROP 2 LAST SIG_NAME NC_PVDDCR_CPU1_P1_DNC6
J 0
(2380 1685);
DISPLAY 0.489362 (2380 1685);
FORCEPROP 2 LASTPROP $XRERR UNIQUE?
J 0
(2335 1675);
DISPLAY 0.638298 (2335 1675);
PAINT MONO (2335 1675);
DISPLAY INVISIBLE (2335 1675);
WIRE 16 -1 (2900 4050)(1950 4050);
FORCEPROP 2 LAST SIG_NAME PVDDCR_CPU1_P1_TEMP0
J 0
(2065 4060);
DISPLAY 0.489362 (2065 4060);
WIRE 16 -1 (2900 3950)(1950 3950);
FORCEPROP 2 LAST SIG_NAME PVDDCR_CPU1_P1_PWM5
J 0
(2065 3960);
DISPLAY 0.489362 (2065 3960);
WIRE 16 -1 (2950 1425)(2000 1425);
FORCEPROP 2 LAST SIG_NAME PVDDCR_CPU1_P1_TEMP0
J 0
(2115 1435);
DISPLAY 0.489362 (2115 1435);
WIRE 16 -1 (2950 1925)(2000 1925);
FORCEPROP 2 LAST SIG_NAME PVDDCR_CPU1_P1_IMON6
J 0
(2115 1935);
DISPLAY 0.489362 (2115 1935);
WIRE 16 -1 (2850 1750)(975 1750);
WIRE 16 -1 (2850 1825)(2850 1750);
FORCEPROP 0 LAST CDS_PHYS_NET_NAME PVCCIN_CPU0_VREF
J 0
(2850 1775);
PAINT MONO (2850 1775);
DISPLAY INVISIBLE (2850 1775);
WIRE 16 -1 (975 1750)(975 1650);
WIRE 16 -1 (2000 1825)(2850 1825);
FORCEPROP 2 LAST SIG_NAME PVDDCR_CPU1_P1_VCCS
J 0
(2115 1835);
DISPLAY 0.489362 (2115 1835);
WIRE 16 -1 (2850 1825)(2950 1825);
WIRE 16 -1 (1925 3000)(1925 3125);
WIRE 16 -1 (2275 3125)(1925 3125);
WIRE 16 -1 (1925 3250)(1925 3125);
WIRE 16 -1 (2600 3125)(2275 3125);
WIRE 16 -1 (2275 3025)(2275 3125);
WIRE 16 -1 (2600 2575)(2600 3125);
WIRE 16 -1 (2950 2575)(2600 2575);
WIRE 16 -1 (1925 2450)(1925 2550);
WIRE 16 -1 (1925 2550)(2250 2550);
WIRE 16 -1 (1925 2800)(1925 2550);
WIRE 16 -1 (2250 2550)(2250 2275);
WIRE 16 -1 (2850 2275)(2250 2275);
FORCEPROP 2 LAST SIG_NAME PVDDCR_CPU1_P1_VCC6
J 0
(2315 2285);
DISPLAY 0.489362 (2315 2285);
FORCEPROP 2 LASTPROP $XRERR UNIQUE?
J 0
(2075 2285);
DISPLAY 0.638298 (2075 2285);
PAINT MONO (2075 2285);
DISPLAY INVISIBLE (2075 2285);
WIRE 16 -1 (2850 2275)(2950 2275);
WIRE 16 -1 (2850 2075)(2850 2275);
WIRE 16 -1 (2950 2075)(2850 2075);
WIRE 16 -1 (5850 2925)(5850 3075);
WIRE 16 -1 (5850 3125)(5850 3075);
WIRE 16 -1 (5475 3075)(5850 3075);
WIRE 16 -1 (5475 2925)(5475 3075);
WIRE 16 -1 (5075 3075)(5475 3075);
WIRE 16 -1 (4675 3075)(5075 3075);
WIRE 16 -1 (5075 3075)(5075 2925);
WIRE 16 -1 (4675 2925)(4675 3075);
WIRE 16 -1 (4675 3075)(4250 3075);
WIRE 16 -1 (4250 2925)(4250 3075);
WIRE 16 -1 (4250 3075)(3975 3075);
WIRE 16 -1 (3975 3075)(3975 2575);
WIRE 16 -1 (3800 2575)(3975 2575);
WIRE 16 -1 (3975 2525)(3975 2575);
WIRE 16 -1 (3800 2525)(3975 2525);
WIRE 16 -1 (5675 3500)(4575 3500);
FORCEPROP 2 LAST SIG_NAME PVDDCR_CPU1_P1_VOS5
J 0
(3865 4325);
DISPLAY 0.489362 (3865 4325);
FORCEPROP 2 LASTPROP $XRERR UNIQUE?
J 0
(3625 4325);
DISPLAY 0.638298 (3625 4325);
PAINT MONO (3625 4325);
DISPLAY INVISIBLE (3625 4325);
WIRE 16 -1 (4575 4300)(4575 3500);
WIRE 16 -1 (3750 4300)(4575 4300);
WIRE 16 -1 (7200 4300)(7775 4300);
FORCEPROP 2 LAST SIG_NAME IND_CPU1_P1_CPL5
J 0
(7340 4310);
DISPLAY 0.489362 (7340 4310);
WIRE 16 -1 (8100 4550)(8100 3500);
WIRE 16 -1 (8300 4550)(8100 4550);
WIRE 16 -1 (8100 4550)(7200 4550);
WIRE 16 -1 (8100 3500)(5875 3500);
WIRE 16 -1 (8300 4550)(8725 4550);
WIRE 16 -1 (8300 4550)(8300 4450);
WIRE 16 -1 (8725 4650)(8725 4550);
WIRE 16 -1 (8725 4450)(8725 4550);
WIRE 16 -1 (5875 1675)(6450 1675);
WIRE 16 -1 (3800 1675)(4625 1675);
WIRE 16 -1 (4625 1675)(4625 775);
WIRE 16 -1 (5850 775)(4625 775);
FORCEPROP 2 LAST SIG_NAME PVDDCR_CPU1_P1_VOS6
J 0
(3915 1700);
DISPLAY 0.489362 (3915 1700);
FORCEPROP 2 LASTPROP $XRERR UNIQUE?
J 0
(3675 1700);
DISPLAY 0.638298 (3675 1700);
PAINT MONO (3675 1700);
DISPLAY INVISIBLE (3675 1700);
WIRE 16 -1 (1475 1625)(2950 1625);
FORCEPROP 2 LAST SIG_NAME PVDDCR_CPU1_P1_LSET6
J 0
(1990 1635);
DISPLAY 0.489362 (1990 1635);
FORCEPROP 2 LASTPROP $XRERR UNIQUE?
J 0
(1750 1635);
DISPLAY 0.638298 (1750 1635);
PAINT MONO (1750 1635);
DISPLAY INVISIBLE (1750 1635);
WIRE 16 -1 (1475 1625)(1475 1525);
WIRE 16 -1 (3800 1475)(4050 1475);
WIRE 16 -1 (4050 1475)(4050 1425);
WIRE 16 -1 (3800 1425)(4050 1425);
WIRE 16 -1 (4050 1425)(4050 1375);
WIRE 16 -1 (4050 1375)(4050 1325);
WIRE 16 -1 (3800 1375)(4050 1375);
WIRE 16 -1 (4050 1325)(4050 1250);
WIRE 16 -1 (3800 1325)(4050 1325);
WIRE 16 -1 (2950 1325)(2000 1325);
FORCEPROP 2 LAST SIG_NAME PVDDCR_CPU1_P1_PWM6
J 0
(2115 1335);
DISPLAY 0.489362 (2115 1335);
DOT 1 (4850 4550);
DOT 1 (4675 2575);
DOT 1 (4000 4050);
DOT 1 (5800 5700);
DOT 1 (8775 1925);
DOT 1 (8775 1500);
DOT 1 (8350 1925);
DOT 1 (8150 1925);
DOT 1 (5850 3075);
DOT 1 (5850 2575);
DOT 1 (5475 3075);
DOT 1 (5475 2575);
DOT 1 (5075 2575);
DOT 1 (4250 3075);
DOT 1 (3975 2575);
DOT 1 (2275 3125);
DOT 1 (2850 2275);
DOT 1 (2850 1825);
DOT 1 (1925 2550);
DOT 1 (4050 1425);
DOT 1 (4050 1375);
DOT 1 (4050 1325);
DOT 1 (4675 3075);
DOT 1 (4000 3950);
DOT 1 (1875 5175);
DOT 1 (1875 5750);
DOT 1 (2800 4450);
DOT 1 (2800 4900);
DOT 1 (2225 5750);
DOT 1 (3925 5200);
DOT 1 (4200 5700);
DOT 1 (4625 5200);
DOT 1 (5025 5200);
DOT 1 (4625 5700);
DOT 1 (5025 5700);
DOT 1 (5425 5200);
DOT 1 (5425 5700);
DOT 1 (5800 5200);
DOT 1 (8100 4550);
DOT 1 (8725 4125);
DOT 1 (8725 4550);
DOT 1 (4000 4000);
DOT 1 (1925 3125);
DOT 1 (5075 3075);
DOT 1 (4925 1925);
DOT 1 (8300 4550);
FORCENOTE
PVDDCR_CPU1_P1_PHASE5
(2975 5725) 0;
DISPLAY LEFT (2975 5725);
DISPLAY 1.021277 (2975 5725);
PAINT WHITE (2975 5725);
FORCENOTE
PGL6303.151HLT
(7200 4850) 0;
DISPLAY LEFT (7200 4850);
DISPLAY 0.638298 (7200 4850);
PAINT WHITE (7200 4850);
FORCENOTE
ISAT:70A@100C
(7200 4800) 0;
DISPLAY LEFT (7200 4800);
DISPLAY 0.638298 (7200 4800);
PAINT WHITE (7200 4800);
FORCENOTE
11.0*7.5*12.5
(7200 4750) 0;
DISPLAY LEFT (7200 4750);
DISPLAY 0.638298 (7200 4750);
PAINT WHITE (7200 4750);
FORCENOTE
2ND=CV+15^0TZ01
(7250 2000) 0;
DISPLAY LEFT (7250 2000);
DISPLAY 0.638298 (7250 2000);
PAINT WHITE (7250 2000);
FORCENOTE
DCR=2-3,0.27M OHM
(7250 2050) 0;
DISPLAY LEFT (7250 2050);
DISPLAY 0.638298 (7250 2050);
PAINT WHITE (7250 2050);
FORCENOTE
DCR=1-4,0.105M OHM
(7200 4700) 0;
DISPLAY LEFT (7200 4700);
DISPLAY 0.638298 (7200 4700);
PAINT WHITE (7200 4700);
FORCENOTE
DCR=2-3,0.27M OHM
(7200 4650) 0;
DISPLAY LEFT (7200 4650);
DISPLAY 0.638298 (7200 4650);
PAINT WHITE (7200 4650);
FORCENOTE
2ND=CV+15^0TZ01
(7200 4600) 0;
DISPLAY LEFT (7200 4600);
DISPLAY 0.638298 (7200 4600);
PAINT WHITE (7200 4600);
FORCENOTE
PVDDCR_CPU1_P1_PHASE6
(3025 3100) 0;
DISPLAY LEFT (3025 3100);
DISPLAY 1.021277 (3025 3100);
PAINT WHITE (3025 3100);
FORCENOTE
PGL6303.151HLT
(7250 2250) 0;
DISPLAY LEFT (7250 2250);
DISPLAY 0.638298 (7250 2250);
PAINT WHITE (7250 2250);
FORCENOTE
ISAT:70A@100C
(7250 2200) 0;
DISPLAY LEFT (7250 2200);
DISPLAY 0.638298 (7250 2200);
PAINT WHITE (7250 2200);
FORCENOTE
11.0*7.5*12.5
(7250 2150) 0;
DISPLAY LEFT (7250 2150);
DISPLAY 0.638298 (7250 2150);
PAINT WHITE (7250 2150);
FORCENOTE
DCR=1-4,0.105M OHM
(7250 2100) 0;
DISPLAY LEFT (7250 2100);
DISPLAY 0.638298 (7250 2100);
PAINT WHITE (7250 2100);
FORCENOTE
DCR=0.17M OHM
(5650 1475) 0;
DISPLAY LEFT (5650 1475);
DISPLAY 0.638298 (5650 1475);
PAINT WHITE (5650 1475);
FORCENOTE
HCME656510Q-221QL
(5650 1625) 0;
DISPLAY LEFT (5650 1625);
DISPLAY 0.638298 (5650 1625);
PAINT WHITE (5650 1625);
FORCENOTE
ISAT:30A@100C
(5650 1575) 0;
DISPLAY LEFT (5650 1575);
DISPLAY 0.638298 (5650 1575);
PAINT WHITE (5650 1575);
FORCENOTE
6.5*6.5*10.0
(5650 1525) 0;
DISPLAY LEFT (5650 1525);
DISPLAY 0.638298 (5650 1525);
PAINT WHITE (5650 1525);
FORCENOTE
2ND=CV+22Y0EZ01
(5650 1425) 0;
DISPLAY LEFT (5650 1425);
DISPLAY 0.638298 (5650 1425);
PAINT WHITE (5650 1425);
QUIT
